FILE_TYPE = MACRO_DRAWING;
SET COLOR_WIRE YELLOW;
SET COLOR_PROP ORANGE;
SET COLOR_DOT WHITE;
SET COLOR_ARC YELLOW;
SET COLOR_BODY GREEN;
SET COLOR_NOTE PURPLE;
SET PROP_DISPLAY VALUE;
SET PAGE_NUMBER P10;
FORCEADD GENOA_SP5..1
(-4350 3700);
FORCEPROP 1 LAST LOCATION U25
J 0
(-4995 6506);
DISPLAY 0.489362 (-4995 6506);
PAINT SKYBLUE (-4995 6506);
FORCEPROP 0 LAST $SEC 1
J 0
(-4975 6550);
DISPLAY 0.680851 (-4975 6550);
PAINT MONO (-4975 6550);
DISPLAY INVISIBLE (-4975 6550);
FORCEPROP 0 LAST CDS_SEC 1
J 0
(-5000 6450);
DISPLAY 1.021277 (-5000 6450);
DISPLAY INVISIBLE (-5000 6450);
FORCEPROP 0 LASTPIN (-5150 3100) $PN BC74
J 2
(-5160 3110);
DISPLAY 0.489362 (-5160 3110);
PAINT MONO (-5160 3110);
FORCEPROP 0 LASTPIN (-5150 3050) $PN BD74
J 2
(-5160 3060);
DISPLAY 0.489362 (-5160 3060);
PAINT MONO (-5160 3060);
FORCEPROP 0 LASTPIN (-5150 1950) $PN BF74
J 2
(-5160 1960);
DISPLAY 0.489362 (-5160 1960);
PAINT MONO (-5160 1960);
FORCEPROP 0 LASTPIN (-5150 1900) $PN BG74
J 2
(-5160 1910);
DISPLAY 0.489362 (-5160 1910);
PAINT MONO (-5160 1910);
FORCEPROP 0 LASTPIN (-5150 2250) $PN AR74
J 2
(-5160 2260);
DISPLAY 0.489362 (-5160 2260);
PAINT MONO (-5160 2260);
FORCEPROP 0 LASTPIN (-5150 2150) $PN AT74
J 2
(-5160 2160);
DISPLAY 0.489362 (-5160 2160);
PAINT MONO (-5160 2160);
FORCEPROP 0 LASTPIN (-5150 2950) $PN AV74
J 2
(-5160 2960);
DISPLAY 0.489362 (-5160 2960);
PAINT MONO (-5160 2960);
FORCEPROP 0 LASTPIN (-5150 2900) $PN AW73
J 2
(-5160 2910);
DISPLAY 0.489362 (-5160 2910);
PAINT MONO (-5160 2910);
FORCEPROP 0 LASTPIN (-5150 2800) $PN BN73
J 2
(-5160 2810);
DISPLAY 0.489362 (-5160 2810);
PAINT MONO (-5160 2810);
FORCEPROP 0 LASTPIN (-5150 1800) $PN AU74
J 2
(-5160 1810);
DISPLAY 0.489362 (-5160 1810);
PAINT MONO (-5160 1810);
FORCEPROP 0 LASTPIN (-5150 1750) $PN AV72
J 2
(-5160 1760);
DISPLAY 0.489362 (-5160 1760);
PAINT MONO (-5160 1760);
FORCEPROP 0 LASTPIN (-5150 1650) $PN BP72
J 2
(-5160 1660);
DISPLAY 0.489362 (-5160 1660);
PAINT MONO (-5160 1660);
FORCEPROP 0 LASTPIN (-5150 3950) $PN AW74
J 2
(-5160 3960);
DISPLAY 0.489362 (-5160 3960);
PAINT MONO (-5160 3960);
FORCEPROP 0 LASTPIN (-5150 3900) $PN AY74
J 2
(-5160 3910);
DISPLAY 0.489362 (-5160 3910);
PAINT MONO (-5160 3910);
FORCEPROP 0 LASTPIN (-5150 3850) $PN AY72
J 2
(-5160 3860);
DISPLAY 0.489362 (-5160 3860);
PAINT MONO (-5160 3860);
FORCEPROP 0 LASTPIN (-5150 3800) $PN BA73
J 2
(-5160 3810);
DISPLAY 0.489362 (-5160 3810);
PAINT MONO (-5160 3810);
FORCEPROP 0 LASTPIN (-5150 3750) $PN BA74
J 2
(-5160 3760);
DISPLAY 0.489362 (-5160 3760);
PAINT MONO (-5160 3760);
FORCEPROP 0 LASTPIN (-5150 3700) $PN BB74
J 2
(-5160 3710);
DISPLAY 0.489362 (-5160 3710);
PAINT MONO (-5160 3710);
FORCEPROP 0 LASTPIN (-5150 3650) $PN BB72
J 2
(-5160 3660);
DISPLAY 0.489362 (-5160 3660);
PAINT MONO (-5160 3660);
FORCEPROP 0 LASTPIN (-3550 2500) $PN AJ74
J 0
(-3540 2510);
DISPLAY 0.489362 (-3540 2510);
PAINT MONO (-3540 2510);
FORCEPROP 0 LASTPIN (-3550 2450) $PN AK72
J 0
(-3540 2460);
DISPLAY 0.489362 (-3540 2460);
PAINT MONO (-3540 2460);
FORCEPROP 0 LASTPIN (-3550 2400) $PN AK74
J 0
(-3540 2410);
DISPLAY 0.489362 (-3540 2410);
PAINT MONO (-3540 2410);
FORCEPROP 0 LASTPIN (-3550 2350) $PN AL73
J 0
(-3540 2360);
DISPLAY 0.489362 (-3540 2360);
PAINT MONO (-3540 2360);
FORCEPROP 0 LASTPIN (-3550 2300) $PN AN74
J 0
(-3540 2310);
DISPLAY 0.489362 (-3540 2310);
PAINT MONO (-3540 2310);
FORCEPROP 0 LASTPIN (-3550 2250) $PN AP72
J 0
(-3540 2260);
DISPLAY 0.489362 (-3540 2260);
PAINT MONO (-3540 2260);
FORCEPROP 0 LASTPIN (-3550 2200) $PN AP74
J 0
(-3540 2210);
DISPLAY 0.489362 (-3540 2210);
PAINT MONO (-3540 2210);
FORCEPROP 0 LASTPIN (-3550 2150) $PN AR73
J 0
(-3540 2160);
DISPLAY 0.489362 (-3540 2160);
PAINT MONO (-3540 2160);
FORCEPROP 0 LASTPIN (-3550 6100) $PN E74
J 0
(-3540 6110);
DISPLAY 0.489362 (-3540 6110);
PAINT MONO (-3540 6110);
FORCEPROP 0 LASTPIN (-3550 6050) $PN F72
J 0
(-3540 6060);
DISPLAY 0.489362 (-3540 6060);
PAINT MONO (-3540 6060);
FORCEPROP 0 LASTPIN (-3550 6000) $PN F74
J 0
(-3540 6010);
DISPLAY 0.489362 (-3540 6010);
PAINT MONO (-3540 6010);
FORCEPROP 0 LASTPIN (-3550 5950) $PN G73
J 0
(-3540 5960);
DISPLAY 0.489362 (-3540 5960);
PAINT MONO (-3540 5960);
FORCEPROP 0 LASTPIN (-3550 5900) $PN J74
J 0
(-3540 5910);
DISPLAY 0.489362 (-3540 5910);
PAINT MONO (-3540 5910);
FORCEPROP 0 LASTPIN (-3550 5850) $PN K72
J 0
(-3540 5860);
DISPLAY 0.489362 (-3540 5860);
PAINT MONO (-3540 5860);
FORCEPROP 0 LASTPIN (-3550 5800) $PN K74
J 0
(-3540 5810);
DISPLAY 0.489362 (-3540 5810);
PAINT MONO (-3540 5810);
FORCEPROP 0 LASTPIN (-3550 5750) $PN L73
J 0
(-3540 5760);
DISPLAY 0.489362 (-3540 5760);
PAINT MONO (-3540 5760);
FORCEPROP 0 LASTPIN (-3550 5650) $PN L74
J 0
(-3540 5660);
DISPLAY 0.489362 (-3540 5660);
PAINT MONO (-3540 5660);
FORCEPROP 0 LASTPIN (-3550 5600) $PN M72
J 0
(-3540 5610);
DISPLAY 0.489362 (-3540 5610);
PAINT MONO (-3540 5610);
FORCEPROP 0 LASTPIN (-3550 5550) $PN M74
J 0
(-3540 5560);
DISPLAY 0.489362 (-3540 5560);
PAINT MONO (-3540 5560);
FORCEPROP 0 LASTPIN (-3550 5500) $PN N73
J 0
(-3540 5510);
DISPLAY 0.489362 (-3540 5510);
PAINT MONO (-3540 5510);
FORCEPROP 0 LASTPIN (-3550 5450) $PN R74
J 0
(-3540 5460);
DISPLAY 0.489362 (-3540 5460);
PAINT MONO (-3540 5460);
FORCEPROP 0 LASTPIN (-3550 5400) $PN T72
J 0
(-3540 5410);
DISPLAY 0.489362 (-3540 5410);
PAINT MONO (-3540 5410);
FORCEPROP 0 LASTPIN (-3550 5350) $PN T74
J 0
(-3540 5360);
DISPLAY 0.489362 (-3540 5360);
PAINT MONO (-3540 5360);
FORCEPROP 0 LASTPIN (-3550 5300) $PN U73
J 0
(-3540 5310);
DISPLAY 0.489362 (-3540 5310);
PAINT MONO (-3540 5310);
FORCEPROP 0 LASTPIN (-3550 5200) $PN U74
J 0
(-3540 5210);
DISPLAY 0.489362 (-3540 5210);
PAINT MONO (-3540 5210);
FORCEPROP 0 LASTPIN (-3550 5150) $PN V72
J 0
(-3540 5160);
DISPLAY 0.489362 (-3540 5160);
PAINT MONO (-3540 5160);
FORCEPROP 0 LASTPIN (-3550 5100) $PN V74
J 0
(-3540 5110);
DISPLAY 0.489362 (-3540 5110);
PAINT MONO (-3540 5110);
FORCEPROP 0 LASTPIN (-3550 5050) $PN W73
J 0
(-3540 5060);
DISPLAY 0.489362 (-3540 5060);
PAINT MONO (-3540 5060);
FORCEPROP 0 LASTPIN (-3550 5000) $PN AA74
J 0
(-3540 5010);
DISPLAY 0.489362 (-3540 5010);
PAINT MONO (-3540 5010);
FORCEPROP 0 LASTPIN (-3550 4950) $PN AB72
J 0
(-3540 4960);
DISPLAY 0.489362 (-3540 4960);
PAINT MONO (-3540 4960);
FORCEPROP 0 LASTPIN (-3550 4900) $PN AB74
J 0
(-3540 4910);
DISPLAY 0.489362 (-3540 4910);
PAINT MONO (-3540 4910);
FORCEPROP 0 LASTPIN (-3550 4850) $PN AC73
J 0
(-3540 4860);
DISPLAY 0.489362 (-3540 4860);
PAINT MONO (-3540 4860);
FORCEPROP 0 LASTPIN (-3550 4750) $PN AC74
J 0
(-3540 4760);
DISPLAY 0.489362 (-3540 4760);
PAINT MONO (-3540 4760);
FORCEPROP 0 LASTPIN (-3550 4700) $PN AD72
J 0
(-3540 4710);
DISPLAY 0.489362 (-3540 4710);
PAINT MONO (-3540 4710);
FORCEPROP 0 LASTPIN (-3550 4650) $PN AD74
J 0
(-3540 4660);
DISPLAY 0.489362 (-3540 4660);
PAINT MONO (-3540 4660);
FORCEPROP 0 LASTPIN (-3550 4600) $PN AE73
J 0
(-3540 4610);
DISPLAY 0.489362 (-3540 4610);
PAINT MONO (-3540 4610);
FORCEPROP 0 LASTPIN (-3550 4550) $PN AG74
J 0
(-3540 4560);
DISPLAY 0.489362 (-3540 4560);
PAINT MONO (-3540 4560);
FORCEPROP 0 LASTPIN (-3550 4500) $PN AH72
J 0
(-3540 4510);
DISPLAY 0.489362 (-3540 4510);
PAINT MONO (-3540 4510);
FORCEPROP 0 LASTPIN (-3550 4450) $PN AH74
J 0
(-3540 4460);
DISPLAY 0.489362 (-3540 4460);
PAINT MONO (-3540 4460);
FORCEPROP 0 LASTPIN (-3550 4400) $PN AJ73
J 0
(-3540 4410);
DISPLAY 0.489362 (-3540 4410);
PAINT MONO (-3540 4410);
FORCEPROP 0 LASTPIN (-5150 6100) $PN G74
J 2
(-5160 6110);
DISPLAY 0.489362 (-5160 6110);
PAINT MONO (-5160 6110);
FORCEPROP 0 LASTPIN (-5150 6000) $PN N74
J 2
(-5160 6010);
DISPLAY 0.489362 (-5160 6010);
PAINT MONO (-5160 6010);
FORCEPROP 0 LASTPIN (-5150 5900) $PN W74
J 2
(-5160 5910);
DISPLAY 0.489362 (-5160 5910);
PAINT MONO (-5160 5910);
FORCEPROP 0 LASTPIN (-5150 5800) $PN AE74
J 2
(-5160 5810);
DISPLAY 0.489362 (-5160 5810);
PAINT MONO (-5160 5810);
FORCEPROP 0 LASTPIN (-5150 5700) $PN AL74
J 2
(-5160 5710);
DISPLAY 0.489362 (-5160 5710);
PAINT MONO (-5160 5710);
FORCEPROP 0 LASTPIN (-5150 5600) $PN J73
J 2
(-5160 5610);
DISPLAY 0.489362 (-5160 5610);
PAINT MONO (-5160 5610);
FORCEPROP 0 LASTPIN (-5150 5500) $PN R73
J 2
(-5160 5510);
DISPLAY 0.489362 (-5160 5510);
PAINT MONO (-5160 5510);
FORCEPROP 0 LASTPIN (-5150 5400) $PN AA73
J 2
(-5160 5410);
DISPLAY 0.489362 (-5160 5410);
PAINT MONO (-5160 5410);
FORCEPROP 0 LASTPIN (-5150 5300) $PN AG73
J 2
(-5160 5310);
DISPLAY 0.489362 (-5160 5310);
PAINT MONO (-5160 5310);
FORCEPROP 0 LASTPIN (-5150 5200) $PN AN73
J 2
(-5160 5210);
DISPLAY 0.489362 (-5160 5210);
PAINT MONO (-5160 5210);
FORCEPROP 0 LASTPIN (-5150 6050) $PN H74
J 2
(-5160 6060);
DISPLAY 0.489362 (-5160 6060);
PAINT MONO (-5160 6060);
FORCEPROP 0 LASTPIN (-5150 5950) $PN P74
J 2
(-5160 5960);
DISPLAY 0.489362 (-5160 5960);
PAINT MONO (-5160 5960);
FORCEPROP 0 LASTPIN (-5150 5850) $PN Y74
J 2
(-5160 5860);
DISPLAY 0.489362 (-5160 5860);
PAINT MONO (-5160 5860);
FORCEPROP 0 LASTPIN (-5150 5750) $PN AF74
J 2
(-5160 5760);
DISPLAY 0.489362 (-5160 5760);
PAINT MONO (-5160 5760);
FORCEPROP 0 LASTPIN (-5150 5650) $PN AM74
J 2
(-5160 5660);
DISPLAY 0.489362 (-5160 5660);
PAINT MONO (-5160 5660);
FORCEPROP 0 LASTPIN (-5150 5550) $PN H72
J 2
(-5160 5560);
DISPLAY 0.489362 (-5160 5560);
PAINT MONO (-5160 5560);
FORCEPROP 0 LASTPIN (-5150 5450) $PN P72
J 2
(-5160 5460);
DISPLAY 0.489362 (-5160 5460);
PAINT MONO (-5160 5460);
FORCEPROP 0 LASTPIN (-5150 5350) $PN Y72
J 2
(-5160 5360);
DISPLAY 0.489362 (-5160 5360);
PAINT MONO (-5160 5360);
FORCEPROP 0 LASTPIN (-5150 5250) $PN AF72
J 2
(-5160 5260);
DISPLAY 0.489362 (-5160 5260);
PAINT MONO (-5160 5260);
FORCEPROP 0 LASTPIN (-5150 5150) $PN AM72
J 2
(-5160 5160);
DISPLAY 0.489362 (-5160 5160);
PAINT MONO (-5160 5160);
FORCEPROP 0 LASTPIN (-5150 2700) $PN BC73
J 2
(-5160 2710);
DISPLAY 0.489362 (-5160 2710);
PAINT MONO (-5160 2710);
FORCEPROP 0 LASTPIN (-5150 2600) $PN BM72
J 2
(-5160 2610);
DISPLAY 0.489362 (-5160 2610);
PAINT MONO (-5160 2610);
FORCEPROP 0 LASTPIN (-5150 2550) $PN BN74
J 2
(-5160 2560);
DISPLAY 0.489362 (-5160 2560);
PAINT MONO (-5160 2560);
FORCEPROP 0 LASTPIN (-5150 2450) $PN BP74
J 2
(-5160 2460);
DISPLAY 0.489362 (-5160 2460);
PAINT MONO (-5160 2460);
FORCEPROP 0 LASTPIN (-5150 1550) $PN BL73
J 2
(-5160 1560);
DISPLAY 0.489362 (-5160 1560);
PAINT MONO (-5160 1560);
FORCEPROP 0 LASTPIN (-5150 1500) $PN BM74
J 2
(-5160 1510);
DISPLAY 0.489362 (-5160 1510);
PAINT MONO (-5160 1510);
FORCEPROP 0 LASTPIN (-5150 1400) $PN BR74
J 2
(-5160 1410);
DISPLAY 0.489362 (-5160 1410);
PAINT MONO (-5160 1410);
FORCEPROP 0 LASTPIN (-5150 3550) $PN BG73
J 2
(-5160 3560);
DISPLAY 0.489362 (-5160 3560);
PAINT MONO (-5160 3560);
FORCEPROP 0 LASTPIN (-5150 3500) $PN BH72
J 2
(-5160 3510);
DISPLAY 0.489362 (-5160 3510);
PAINT MONO (-5160 3510);
FORCEPROP 0 LASTPIN (-5150 3450) $PN BH74
J 2
(-5160 3460);
DISPLAY 0.489362 (-5160 3460);
PAINT MONO (-5160 3460);
FORCEPROP 0 LASTPIN (-5150 3400) $PN BJ74
J 2
(-5160 3410);
DISPLAY 0.489362 (-5160 3410);
PAINT MONO (-5160 3410);
FORCEPROP 0 LASTPIN (-5150 3350) $PN BJ73
J 2
(-5160 3360);
DISPLAY 0.489362 (-5160 3360);
PAINT MONO (-5160 3360);
FORCEPROP 0 LASTPIN (-5150 3300) $PN BK72
J 2
(-5160 3310);
DISPLAY 0.489362 (-5160 3310);
PAINT MONO (-5160 3310);
FORCEPROP 0 LASTPIN (-5150 3250) $PN BK74
J 2
(-5160 3260);
DISPLAY 0.489362 (-5160 3260);
PAINT MONO (-5160 3260);
FORCEPROP 0 LASTPIN (-3550 2050) $PN BY74
J 0
(-3540 2060);
DISPLAY 0.489362 (-3540 2060);
PAINT MONO (-3540 2060);
FORCEPROP 0 LASTPIN (-3550 2000) $PN CA73
J 0
(-3540 2010);
DISPLAY 0.489362 (-3540 2010);
PAINT MONO (-3540 2010);
FORCEPROP 0 LASTPIN (-3550 1950) $PN CA74
J 0
(-3540 1960);
DISPLAY 0.489362 (-3540 1960);
PAINT MONO (-3540 1960);
FORCEPROP 0 LASTPIN (-3550 1900) $PN CB72
J 0
(-3540 1910);
DISPLAY 0.489362 (-3540 1910);
PAINT MONO (-3540 1910);
FORCEPROP 0 LASTPIN (-3550 1850) $PN BT74
J 0
(-3540 1860);
DISPLAY 0.489362 (-3540 1860);
PAINT MONO (-3540 1860);
FORCEPROP 0 LASTPIN (-3550 1800) $PN BU73
J 0
(-3540 1810);
DISPLAY 0.489362 (-3540 1810);
PAINT MONO (-3540 1810);
FORCEPROP 0 LASTPIN (-3550 1750) $PN BU74
J 0
(-3540 1760);
DISPLAY 0.489362 (-3540 1760);
PAINT MONO (-3540 1760);
FORCEPROP 0 LASTPIN (-3550 1700) $PN BV72
J 0
(-3540 1710);
DISPLAY 0.489362 (-3540 1710);
PAINT MONO (-3540 1710);
FORCEPROP 0 LASTPIN (-3550 4300) $PN CB74
J 0
(-3540 4310);
DISPLAY 0.489362 (-3540 4310);
PAINT MONO (-3540 4310);
FORCEPROP 0 LASTPIN (-3550 4250) $PN CC73
J 0
(-3540 4260);
DISPLAY 0.489362 (-3540 4260);
PAINT MONO (-3540 4260);
FORCEPROP 0 LASTPIN (-3550 4200) $PN CC74
J 0
(-3540 4210);
DISPLAY 0.489362 (-3540 4210);
PAINT MONO (-3540 4210);
FORCEPROP 0 LASTPIN (-3550 4150) $PN CD72
J 0
(-3540 4160);
DISPLAY 0.489362 (-3540 4160);
PAINT MONO (-3540 4160);
FORCEPROP 0 LASTPIN (-3550 4100) $PN CF74
J 0
(-3540 4110);
DISPLAY 0.489362 (-3540 4110);
PAINT MONO (-3540 4110);
FORCEPROP 0 LASTPIN (-3550 4050) $PN CG73
J 0
(-3540 4060);
DISPLAY 0.489362 (-3540 4060);
PAINT MONO (-3540 4060);
FORCEPROP 0 LASTPIN (-3550 4000) $PN CG74
J 0
(-3540 4010);
DISPLAY 0.489362 (-3540 4010);
PAINT MONO (-3540 4010);
FORCEPROP 0 LASTPIN (-3550 3950) $PN CH72
J 0
(-3540 3960);
DISPLAY 0.489362 (-3540 3960);
PAINT MONO (-3540 3960);
FORCEPROP 0 LASTPIN (-3550 3850) $PN CH74
J 0
(-3540 3860);
DISPLAY 0.489362 (-3540 3860);
PAINT MONO (-3540 3860);
FORCEPROP 0 LASTPIN (-3550 3800) $PN CJ73
J 0
(-3540 3810);
DISPLAY 0.489362 (-3540 3810);
PAINT MONO (-3540 3810);
FORCEPROP 0 LASTPIN (-3550 3750) $PN CJ74
J 0
(-3540 3760);
DISPLAY 0.489362 (-3540 3760);
PAINT MONO (-3540 3760);
FORCEPROP 0 LASTPIN (-3550 3700) $PN CK72
J 0
(-3540 3710);
DISPLAY 0.489362 (-3540 3710);
PAINT MONO (-3540 3710);
FORCEPROP 0 LASTPIN (-3550 3650) $PN CM74
J 0
(-3540 3660);
DISPLAY 0.489362 (-3540 3660);
PAINT MONO (-3540 3660);
FORCEPROP 0 LASTPIN (-3550 3600) $PN CN73
J 0
(-3540 3610);
DISPLAY 0.489362 (-3540 3610);
PAINT MONO (-3540 3610);
FORCEPROP 0 LASTPIN (-3550 3550) $PN CN74
J 0
(-3540 3560);
DISPLAY 0.489362 (-3540 3560);
PAINT MONO (-3540 3560);
FORCEPROP 0 LASTPIN (-3550 3500) $PN CP72
J 0
(-3540 3510);
DISPLAY 0.489362 (-3540 3510);
PAINT MONO (-3540 3510);
FORCEPROP 0 LASTPIN (-3550 3400) $PN CP74
J 0
(-3540 3410);
DISPLAY 0.489362 (-3540 3410);
PAINT MONO (-3540 3410);
FORCEPROP 0 LASTPIN (-3550 3350) $PN CR73
J 0
(-3540 3360);
DISPLAY 0.489362 (-3540 3360);
PAINT MONO (-3540 3360);
FORCEPROP 0 LASTPIN (-3550 3300) $PN CR74
J 0
(-3540 3310);
DISPLAY 0.489362 (-3540 3310);
PAINT MONO (-3540 3310);
FORCEPROP 0 LASTPIN (-3550 3250) $PN CT72
J 0
(-3540 3260);
DISPLAY 0.489362 (-3540 3260);
PAINT MONO (-3540 3260);
FORCEPROP 0 LASTPIN (-3550 3200) $PN CV74
J 0
(-3540 3210);
DISPLAY 0.489362 (-3540 3210);
PAINT MONO (-3540 3210);
FORCEPROP 0 LASTPIN (-3550 3150) $PN CW73
J 0
(-3540 3160);
DISPLAY 0.489362 (-3540 3160);
PAINT MONO (-3540 3160);
FORCEPROP 0 LASTPIN (-3550 3100) $PN CW74
J 0
(-3540 3110);
DISPLAY 0.489362 (-3540 3110);
PAINT MONO (-3540 3110);
FORCEPROP 0 LASTPIN (-3550 3050) $PN CY72
J 0
(-3540 3060);
DISPLAY 0.489362 (-3540 3060);
PAINT MONO (-3540 3060);
FORCEPROP 0 LASTPIN (-3550 2950) $PN CY74
J 0
(-3540 2960);
DISPLAY 0.489362 (-3540 2960);
PAINT MONO (-3540 2960);
FORCEPROP 0 LASTPIN (-3550 2900) $PN DA73
J 0
(-3540 2910);
DISPLAY 0.489362 (-3540 2910);
PAINT MONO (-3540 2910);
FORCEPROP 0 LASTPIN (-3550 2850) $PN DA74
J 0
(-3540 2860);
DISPLAY 0.489362 (-3540 2860);
PAINT MONO (-3540 2860);
FORCEPROP 0 LASTPIN (-3550 2800) $PN DB72
J 0
(-3540 2810);
DISPLAY 0.489362 (-3540 2810);
PAINT MONO (-3540 2810);
FORCEPROP 0 LASTPIN (-3550 2750) $PN DD74
J 0
(-3540 2760);
DISPLAY 0.489362 (-3540 2760);
PAINT MONO (-3540 2760);
FORCEPROP 0 LASTPIN (-3550 2700) $PN DE73
J 0
(-3540 2710);
DISPLAY 0.489362 (-3540 2710);
PAINT MONO (-3540 2710);
FORCEPROP 0 LASTPIN (-3550 2650) $PN DE74
J 0
(-3540 2660);
DISPLAY 0.489362 (-3540 2660);
PAINT MONO (-3540 2660);
FORCEPROP 0 LASTPIN (-3550 2600) $PN DF74
J 0
(-3540 2610);
DISPLAY 0.489362 (-3540 2610);
PAINT MONO (-3540 2610);
FORCEPROP 0 LASTPIN (-5150 5050) $PN CD74
J 2
(-5160 5060);
DISPLAY 0.489362 (-5160 5060);
PAINT MONO (-5160 5060);
FORCEPROP 0 LASTPIN (-5150 4950) $PN CK74
J 2
(-5160 4960);
DISPLAY 0.489362 (-5160 4960);
PAINT MONO (-5160 4960);
FORCEPROP 0 LASTPIN (-5150 4850) $PN CT74
J 2
(-5160 4860);
DISPLAY 0.489362 (-5160 4860);
PAINT MONO (-5160 4860);
FORCEPROP 0 LASTPIN (-5150 4750) $PN DB74
J 2
(-5160 4760);
DISPLAY 0.489362 (-5160 4760);
PAINT MONO (-5160 4760);
FORCEPROP 0 LASTPIN (-5150 4650) $PN BY72
J 2
(-5160 4660);
DISPLAY 0.489362 (-5160 4660);
PAINT MONO (-5160 4660);
FORCEPROP 0 LASTPIN (-5150 4550) $PN CF72
J 2
(-5160 4560);
DISPLAY 0.489362 (-5160 4560);
PAINT MONO (-5160 4560);
FORCEPROP 0 LASTPIN (-5150 4450) $PN CM72
J 2
(-5160 4460);
DISPLAY 0.489362 (-5160 4460);
PAINT MONO (-5160 4460);
FORCEPROP 0 LASTPIN (-5150 4350) $PN CV72
J 2
(-5160 4360);
DISPLAY 0.489362 (-5160 4360);
PAINT MONO (-5160 4360);
FORCEPROP 0 LASTPIN (-5150 4250) $PN DD72
J 2
(-5160 4260);
DISPLAY 0.489362 (-5160 4260);
PAINT MONO (-5160 4260);
FORCEPROP 0 LASTPIN (-5150 4150) $PN BV74
J 2
(-5160 4160);
DISPLAY 0.489362 (-5160 4160);
PAINT MONO (-5160 4160);
FORCEPROP 0 LASTPIN (-5150 5000) $PN CE74
J 2
(-5160 5010);
DISPLAY 0.489362 (-5160 5010);
PAINT MONO (-5160 5010);
FORCEPROP 0 LASTPIN (-5150 4900) $PN CL74
J 2
(-5160 4910);
DISPLAY 0.489362 (-5160 4910);
PAINT MONO (-5160 4910);
FORCEPROP 0 LASTPIN (-5150 4800) $PN CU74
J 2
(-5160 4810);
DISPLAY 0.489362 (-5160 4810);
PAINT MONO (-5160 4810);
FORCEPROP 0 LASTPIN (-5150 4700) $PN DC74
J 2
(-5160 4710);
DISPLAY 0.489362 (-5160 4710);
PAINT MONO (-5160 4710);
FORCEPROP 0 LASTPIN (-5150 4600) $PN BW73
J 2
(-5160 4610);
DISPLAY 0.489362 (-5160 4610);
PAINT MONO (-5160 4610);
FORCEPROP 0 LASTPIN (-5150 4500) $PN CE73
J 2
(-5160 4510);
DISPLAY 0.489362 (-5160 4510);
PAINT MONO (-5160 4510);
FORCEPROP 0 LASTPIN (-5150 4400) $PN CL73
J 2
(-5160 4410);
DISPLAY 0.489362 (-5160 4410);
PAINT MONO (-5160 4410);
FORCEPROP 0 LASTPIN (-5150 4300) $PN CU73
J 2
(-5160 4310);
DISPLAY 0.489362 (-5160 4310);
PAINT MONO (-5160 4310);
FORCEPROP 0 LASTPIN (-5150 4200) $PN DC73
J 2
(-5160 4210);
DISPLAY 0.489362 (-5160 4210);
PAINT MONO (-5160 4210);
FORCEPROP 0 LASTPIN (-5150 4100) $PN BW74
J 2
(-5160 4110);
DISPLAY 0.489362 (-5160 4110);
PAINT MONO (-5160 4110);
FORCEPROP 0 LASTPIN (-5150 2350) $PN BL74
J 2
(-5160 2360);
DISPLAY 0.489362 (-5160 2360);
PAINT MONO (-5160 2360);
FORCEPROP 0 LASTPIN (-5150 1300) $PN BF72
J 2
(-5160 1310);
DISPLAY 0.489362 (-5160 1310);
PAINT MONO (-5160 1310);
FORCEPROP 0 LASTPIN (-5150 1250) $PN C60
J 2
(-5160 1260);
DISPLAY 0.489362 (-5160 1260);
PAINT MONO (-5160 1260);
FORCEPROP 2 LAST PART_TYPE SMLF
J 0
(-5000 6400);
DISPLAY 1.021277 (-5000 6400);
FORCEPROP 1 LAST MATERIAL IO
J 0
(-4995 6232);
DISPLAY 0.489362 (-4995 6232);
PAINT SKYBLUE (-4995 6232);
FORCEPROP 2 LAST VALUE SOCKET6096_13568-001
J 0
(-5000 6300);
DISPLAY 0.489362 (-5000 6300);
PAINT SKYBLUE (-5000 6300);
FORCEPROP 2 LAST CDS_LIB pure_quanta
J 0
(-4350 3700);
DISPLAY INVISIBLE (-4350 3700);
FORCEPROP 1 LAST NEEDS_NO_SIZE TRUE
J 0
(-4350 3700);
DISPLAY 0.723404 (-4350 3700);
PAINT GREEN (-4350 3700);
DISPLAY INVISIBLE (-4350 3700);
FORCEPROP 1 LAST CDS_LMAN_SYM_OUTLINE -650,2500,650,-2500
J 0
(-4350 3700);
DISPLAY 0.468085 (-4350 3700);
PAINT GREEN (-4350 3700);
DISPLAY INVISIBLE (-4350 3700);
FORCEPROP 1 LAST PATH I200
J 0
(-4350 3700);
DISPLAY 0.723404 (-4350 3700);
PAINT GREEN (-4350 3700);
DISPLAY INVISIBLE (-4350 3700);
FORCEPROP 1 LAST PART_NUMBER DGA^6000030
J 0
(-4995 6359);
DISPLAY 0.489362 (-4995 6359);
PAINT SKYBLUE (-4995 6359);
DISPLAY INVISIBLE (-4995 6359);
FORCEADD OFFPAGE..3
(-2300 6125);
FORCEPROP 2 LAST $XR0 86 
J 0
(-2086 6125);
DISPLAY 0.638298 (-2086 6125);
PAINT MONO (-2086 6125);
FORCEPROP 2 LAST CDS_LIB mstr_standard
J 0
(-2300 6125);
DISPLAY INVISIBLE (-2300 6125);
FORCEPROP 1 LAST OFFPAGE TRUE
J 0
(-1975 6000);
DISPLAY 0.872340 (-1975 6000);
PAINT GREEN (-1975 6000);
DISPLAY INVISIBLE (-1975 6000);
FORCEPROP 1 LAST COMMENT_BODY TRUE
J 0
(-2350 6025);
DISPLAY 0.872340 (-2350 6025);
PAINT GREEN (-2350 6025);
DISPLAY INVISIBLE (-2350 6025);
FORCEPROP 2 LAST PATH I682
J 0
(-2075 6175);
DISPLAY 1.021277 (-2075 6175);
DISPLAY INVISIBLE (-2075 6175);
FORCEADD TAP..1
(-3025 6100);
FORCEPROP 3 LASTPIN (-3075 6100) SIG_NAME M_A_CPU0_SA_DQ<0>
J 0
(-3065 6110);
DISPLAY 0.659574 (-3065 6110);
PAINT MONO (-3065 6110);
DISPLAY INVISIBLE (-3065 6110);
FORCEPROP 1 LASTPIN (-3075 6100) BN 0
J 0
(-3087 6108);
DISPLAY 0.489362 (-3087 6108);
PAINT MONO (-3087 6108);
FORCEPROP 2 LAST CDS_LIB mstr_standard
J 0
(-3025 6100);
DISPLAY INVISIBLE (-3025 6100);
FORCEPROP 1 LAST BODY_TYPE PLUMBING
J 0
(-3025 6150);
DISPLAY 0.872340 (-3025 6150);
PAINT GREEN (-3025 6150);
DISPLAY INVISIBLE (-3025 6150);
FORCEPROP 1 LAST HDL_TAP TRUE
J 0
(-2700 5975);
DISPLAY 0.872340 (-2700 5975);
DISPLAY INVISIBLE (-2700 5975);
FORCEPROP 1 LAST PATH I683
J 0
(-3027 6100);
DISPLAY 0.872340 (-3027 6100);
PAINT GREEN (-3027 6100);
DISPLAY INVISIBLE (-3027 6100);
FORCEADD TAP..1
(-3025 5950);
FORCEPROP 3 LASTPIN (-3075 5950) SIG_NAME M_A_CPU0_SA_DQ<3>
J 0
(-3065 5960);
DISPLAY 0.659574 (-3065 5960);
PAINT MONO (-3065 5960);
DISPLAY INVISIBLE (-3065 5960);
FORCEPROP 1 LASTPIN (-3075 5950) BN 3
J 0
(-3087 5958);
DISPLAY 0.489362 (-3087 5958);
PAINT MONO (-3087 5958);
FORCEPROP 2 LAST CDS_LIB mstr_standard
J 0
(-3025 5950);
DISPLAY INVISIBLE (-3025 5950);
FORCEPROP 1 LAST BODY_TYPE PLUMBING
J 0
(-3025 6000);
DISPLAY 0.872340 (-3025 6000);
PAINT GREEN (-3025 6000);
DISPLAY INVISIBLE (-3025 6000);
FORCEPROP 1 LAST HDL_TAP TRUE
J 0
(-2700 5825);
DISPLAY 0.872340 (-2700 5825);
DISPLAY INVISIBLE (-2700 5825);
FORCEPROP 1 LAST PATH I684
J 0
(-3027 5950);
DISPLAY 0.872340 (-3027 5950);
PAINT GREEN (-3027 5950);
DISPLAY INVISIBLE (-3027 5950);
FORCEADD TAP..1
(-3025 6000);
FORCEPROP 3 LASTPIN (-3075 6000) SIG_NAME M_A_CPU0_SA_DQ<2>
J 0
(-3065 6010);
DISPLAY 0.659574 (-3065 6010);
PAINT MONO (-3065 6010);
DISPLAY INVISIBLE (-3065 6010);
FORCEPROP 1 LASTPIN (-3075 6000) BN 2
J 0
(-3087 6008);
DISPLAY 0.489362 (-3087 6008);
PAINT MONO (-3087 6008);
FORCEPROP 2 LAST CDS_LIB mstr_standard
J 0
(-3025 6000);
DISPLAY INVISIBLE (-3025 6000);
FORCEPROP 1 LAST BODY_TYPE PLUMBING
J 0
(-3025 6050);
DISPLAY 0.872340 (-3025 6050);
PAINT GREEN (-3025 6050);
DISPLAY INVISIBLE (-3025 6050);
FORCEPROP 1 LAST HDL_TAP TRUE
J 0
(-2700 5875);
DISPLAY 0.872340 (-2700 5875);
DISPLAY INVISIBLE (-2700 5875);
FORCEPROP 1 LAST PATH I685
J 0
(-3027 6000);
DISPLAY 0.872340 (-3027 6000);
PAINT GREEN (-3027 6000);
DISPLAY INVISIBLE (-3027 6000);
FORCEADD TAP..1
(-3025 6050);
FORCEPROP 3 LASTPIN (-3075 6050) SIG_NAME M_A_CPU0_SA_DQ<1>
J 0
(-3065 6060);
DISPLAY 0.659574 (-3065 6060);
PAINT MONO (-3065 6060);
DISPLAY INVISIBLE (-3065 6060);
FORCEPROP 1 LASTPIN (-3075 6050) BN 1
J 0
(-3087 6058);
DISPLAY 0.489362 (-3087 6058);
PAINT MONO (-3087 6058);
FORCEPROP 2 LAST CDS_LIB mstr_standard
J 0
(-3025 6050);
DISPLAY INVISIBLE (-3025 6050);
FORCEPROP 1 LAST BODY_TYPE PLUMBING
J 0
(-3025 6100);
DISPLAY 0.872340 (-3025 6100);
PAINT GREEN (-3025 6100);
DISPLAY INVISIBLE (-3025 6100);
FORCEPROP 1 LAST HDL_TAP TRUE
J 0
(-2700 5925);
DISPLAY 0.872340 (-2700 5925);
DISPLAY INVISIBLE (-2700 5925);
FORCEPROP 1 LAST PATH I686
J 0
(-3027 6050);
DISPLAY 0.872340 (-3027 6050);
PAINT GREEN (-3027 6050);
DISPLAY INVISIBLE (-3027 6050);
FORCEADD TAP..1
(-3025 5900);
FORCEPROP 3 LASTPIN (-3075 5900) SIG_NAME M_A_CPU0_SA_DQ<4>
J 0
(-3065 5910);
DISPLAY 0.659574 (-3065 5910);
PAINT MONO (-3065 5910);
DISPLAY INVISIBLE (-3065 5910);
FORCEPROP 1 LASTPIN (-3075 5900) BN 4
J 0
(-3087 5908);
DISPLAY 0.489362 (-3087 5908);
PAINT MONO (-3087 5908);
FORCEPROP 2 LAST CDS_LIB mstr_standard
J 0
(-3025 5900);
DISPLAY INVISIBLE (-3025 5900);
FORCEPROP 1 LAST BODY_TYPE PLUMBING
J 0
(-3025 5950);
DISPLAY 0.872340 (-3025 5950);
PAINT GREEN (-3025 5950);
DISPLAY INVISIBLE (-3025 5950);
FORCEPROP 1 LAST HDL_TAP TRUE
J 0
(-2700 5775);
DISPLAY 0.872340 (-2700 5775);
DISPLAY INVISIBLE (-2700 5775);
FORCEPROP 1 LAST PATH I687
J 0
(-3027 5900);
DISPLAY 0.872340 (-3027 5900);
PAINT GREEN (-3027 5900);
DISPLAY INVISIBLE (-3027 5900);
FORCEADD TAP..1
(-3025 5850);
FORCEPROP 3 LASTPIN (-3075 5850) SIG_NAME M_A_CPU0_SA_DQ<5>
J 0
(-3065 5860);
DISPLAY 0.659574 (-3065 5860);
PAINT MONO (-3065 5860);
DISPLAY INVISIBLE (-3065 5860);
FORCEPROP 1 LASTPIN (-3075 5850) BN 5
J 0
(-3087 5858);
DISPLAY 0.489362 (-3087 5858);
PAINT MONO (-3087 5858);
FORCEPROP 2 LAST CDS_LIB mstr_standard
J 0
(-3025 5850);
DISPLAY INVISIBLE (-3025 5850);
FORCEPROP 1 LAST BODY_TYPE PLUMBING
J 0
(-3025 5900);
DISPLAY 0.872340 (-3025 5900);
PAINT GREEN (-3025 5900);
DISPLAY INVISIBLE (-3025 5900);
FORCEPROP 1 LAST HDL_TAP TRUE
J 0
(-2700 5725);
DISPLAY 0.872340 (-2700 5725);
DISPLAY INVISIBLE (-2700 5725);
FORCEPROP 1 LAST PATH I688
J 0
(-3027 5850);
DISPLAY 0.872340 (-3027 5850);
PAINT GREEN (-3027 5850);
DISPLAY INVISIBLE (-3027 5850);
FORCEADD TAP..1
(-3025 5650);
FORCEPROP 3 LASTPIN (-3075 5650) SIG_NAME M_A_CPU0_SA_DQ<8>
J 0
(-3065 5660);
DISPLAY 0.659574 (-3065 5660);
PAINT MONO (-3065 5660);
DISPLAY INVISIBLE (-3065 5660);
FORCEPROP 1 LASTPIN (-3075 5650) BN 8
J 0
(-3087 5658);
DISPLAY 0.489362 (-3087 5658);
PAINT MONO (-3087 5658);
FORCEPROP 2 LAST CDS_LIB mstr_standard
J 0
(-3025 5650);
DISPLAY INVISIBLE (-3025 5650);
FORCEPROP 1 LAST BODY_TYPE PLUMBING
J 0
(-3025 5700);
DISPLAY 0.872340 (-3025 5700);
PAINT GREEN (-3025 5700);
DISPLAY INVISIBLE (-3025 5700);
FORCEPROP 1 LAST HDL_TAP TRUE
J 0
(-2700 5525);
DISPLAY 0.872340 (-2700 5525);
DISPLAY INVISIBLE (-2700 5525);
FORCEPROP 1 LAST PATH I689
J 0
(-3027 5650);
DISPLAY 0.872340 (-3027 5650);
PAINT GREEN (-3027 5650);
DISPLAY INVISIBLE (-3027 5650);
FORCEADD TAP..1
(-3025 5750);
FORCEPROP 3 LASTPIN (-3075 5750) SIG_NAME M_A_CPU0_SA_DQ<7>
J 0
(-3065 5760);
DISPLAY 0.659574 (-3065 5760);
PAINT MONO (-3065 5760);
DISPLAY INVISIBLE (-3065 5760);
FORCEPROP 1 LASTPIN (-3075 5750) BN 7
J 0
(-3087 5758);
DISPLAY 0.489362 (-3087 5758);
PAINT MONO (-3087 5758);
FORCEPROP 2 LAST CDS_LIB mstr_standard
J 0
(-3025 5750);
DISPLAY INVISIBLE (-3025 5750);
FORCEPROP 1 LAST BODY_TYPE PLUMBING
J 0
(-3025 5800);
DISPLAY 0.872340 (-3025 5800);
PAINT GREEN (-3025 5800);
DISPLAY INVISIBLE (-3025 5800);
FORCEPROP 1 LAST HDL_TAP TRUE
J 0
(-2700 5625);
DISPLAY 0.872340 (-2700 5625);
DISPLAY INVISIBLE (-2700 5625);
FORCEPROP 1 LAST PATH I690
J 0
(-3027 5750);
DISPLAY 0.872340 (-3027 5750);
PAINT GREEN (-3027 5750);
DISPLAY INVISIBLE (-3027 5750);
FORCEADD TAP..1
(-3025 5800);
FORCEPROP 3 LASTPIN (-3075 5800) SIG_NAME M_A_CPU0_SA_DQ<6>
J 0
(-3065 5810);
DISPLAY 0.659574 (-3065 5810);
PAINT MONO (-3065 5810);
DISPLAY INVISIBLE (-3065 5810);
FORCEPROP 1 LASTPIN (-3075 5800) BN 6
J 0
(-3087 5808);
DISPLAY 0.489362 (-3087 5808);
PAINT MONO (-3087 5808);
FORCEPROP 2 LAST CDS_LIB mstr_standard
J 0
(-3025 5800);
DISPLAY INVISIBLE (-3025 5800);
FORCEPROP 1 LAST BODY_TYPE PLUMBING
J 0
(-3025 5850);
DISPLAY 0.872340 (-3025 5850);
PAINT GREEN (-3025 5850);
DISPLAY INVISIBLE (-3025 5850);
FORCEPROP 1 LAST HDL_TAP TRUE
J 0
(-2700 5675);
DISPLAY 0.872340 (-2700 5675);
DISPLAY INVISIBLE (-2700 5675);
FORCEPROP 1 LAST PATH I691
J 0
(-3027 5800);
DISPLAY 0.872340 (-3027 5800);
PAINT GREEN (-3027 5800);
DISPLAY INVISIBLE (-3027 5800);
FORCEADD TAP..1
(-3025 5600);
FORCEPROP 3 LASTPIN (-3075 5600) SIG_NAME M_A_CPU0_SA_DQ<9>
J 0
(-3065 5610);
DISPLAY 0.659574 (-3065 5610);
PAINT MONO (-3065 5610);
DISPLAY INVISIBLE (-3065 5610);
FORCEPROP 1 LASTPIN (-3075 5600) BN 9
J 0
(-3087 5608);
DISPLAY 0.489362 (-3087 5608);
PAINT MONO (-3087 5608);
FORCEPROP 2 LAST CDS_LIB mstr_standard
J 0
(-3025 5600);
DISPLAY INVISIBLE (-3025 5600);
FORCEPROP 1 LAST BODY_TYPE PLUMBING
J 0
(-3025 5650);
DISPLAY 0.872340 (-3025 5650);
PAINT GREEN (-3025 5650);
DISPLAY INVISIBLE (-3025 5650);
FORCEPROP 1 LAST HDL_TAP TRUE
J 0
(-2700 5475);
DISPLAY 0.872340 (-2700 5475);
DISPLAY INVISIBLE (-2700 5475);
FORCEPROP 1 LAST PATH I692
J 0
(-3027 5600);
DISPLAY 0.872340 (-3027 5600);
PAINT GREEN (-3027 5600);
DISPLAY INVISIBLE (-3027 5600);
FORCEADD TAP..1
(-3025 5400);
FORCEPROP 3 LASTPIN (-3075 5400) SIG_NAME M_A_CPU0_SA_DQ<13>
J 0
(-3065 5410);
DISPLAY 0.659574 (-3065 5410);
PAINT MONO (-3065 5410);
DISPLAY INVISIBLE (-3065 5410);
FORCEPROP 1 LASTPIN (-3075 5400) BN 13
J 0
(-3087 5408);
DISPLAY 0.489362 (-3087 5408);
PAINT MONO (-3087 5408);
FORCEPROP 2 LAST CDS_LIB mstr_standard
J 0
(-3025 5400);
DISPLAY INVISIBLE (-3025 5400);
FORCEPROP 1 LAST BODY_TYPE PLUMBING
J 0
(-3025 5450);
DISPLAY 0.872340 (-3025 5450);
PAINT GREEN (-3025 5450);
DISPLAY INVISIBLE (-3025 5450);
FORCEPROP 1 LAST HDL_TAP TRUE
J 0
(-2700 5275);
DISPLAY 0.872340 (-2700 5275);
DISPLAY INVISIBLE (-2700 5275);
FORCEPROP 1 LAST PATH I693
J 0
(-3027 5400);
DISPLAY 0.872340 (-3027 5400);
PAINT GREEN (-3027 5400);
DISPLAY INVISIBLE (-3027 5400);
FORCEADD TAP..1
(-3025 5450);
FORCEPROP 3 LASTPIN (-3075 5450) SIG_NAME M_A_CPU0_SA_DQ<12>
J 0
(-3065 5460);
DISPLAY 0.659574 (-3065 5460);
PAINT MONO (-3065 5460);
DISPLAY INVISIBLE (-3065 5460);
FORCEPROP 1 LASTPIN (-3075 5450) BN 12
J 0
(-3087 5458);
DISPLAY 0.489362 (-3087 5458);
PAINT MONO (-3087 5458);
FORCEPROP 2 LAST CDS_LIB mstr_standard
J 0
(-3025 5450);
DISPLAY INVISIBLE (-3025 5450);
FORCEPROP 1 LAST BODY_TYPE PLUMBING
J 0
(-3025 5500);
DISPLAY 0.872340 (-3025 5500);
PAINT GREEN (-3025 5500);
DISPLAY INVISIBLE (-3025 5500);
FORCEPROP 1 LAST HDL_TAP TRUE
J 0
(-2700 5325);
DISPLAY 0.872340 (-2700 5325);
DISPLAY INVISIBLE (-2700 5325);
FORCEPROP 1 LAST PATH I694
J 0
(-3027 5450);
DISPLAY 0.872340 (-3027 5450);
PAINT GREEN (-3027 5450);
DISPLAY INVISIBLE (-3027 5450);
FORCEADD TAP..1
(-3025 5500);
FORCEPROP 3 LASTPIN (-3075 5500) SIG_NAME M_A_CPU0_SA_DQ<11>
J 0
(-3065 5510);
DISPLAY 0.659574 (-3065 5510);
PAINT MONO (-3065 5510);
DISPLAY INVISIBLE (-3065 5510);
FORCEPROP 1 LASTPIN (-3075 5500) BN 11
J 0
(-3087 5508);
DISPLAY 0.489362 (-3087 5508);
PAINT MONO (-3087 5508);
FORCEPROP 2 LAST CDS_LIB mstr_standard
J 0
(-3025 5500);
DISPLAY INVISIBLE (-3025 5500);
FORCEPROP 1 LAST BODY_TYPE PLUMBING
J 0
(-3025 5550);
DISPLAY 0.872340 (-3025 5550);
PAINT GREEN (-3025 5550);
DISPLAY INVISIBLE (-3025 5550);
FORCEPROP 1 LAST HDL_TAP TRUE
J 0
(-2700 5375);
DISPLAY 0.872340 (-2700 5375);
DISPLAY INVISIBLE (-2700 5375);
FORCEPROP 1 LAST PATH I695
J 0
(-3027 5500);
DISPLAY 0.872340 (-3027 5500);
PAINT GREEN (-3027 5500);
DISPLAY INVISIBLE (-3027 5500);
FORCEADD TAP..1
(-3025 5550);
FORCEPROP 3 LASTPIN (-3075 5550) SIG_NAME M_A_CPU0_SA_DQ<10>
J 0
(-3065 5560);
DISPLAY 0.659574 (-3065 5560);
PAINT MONO (-3065 5560);
DISPLAY INVISIBLE (-3065 5560);
FORCEPROP 1 LASTPIN (-3075 5550) BN 10
J 0
(-3087 5558);
DISPLAY 0.489362 (-3087 5558);
PAINT MONO (-3087 5558);
FORCEPROP 2 LAST CDS_LIB mstr_standard
J 0
(-3025 5550);
DISPLAY INVISIBLE (-3025 5550);
FORCEPROP 1 LAST BODY_TYPE PLUMBING
J 0
(-3025 5600);
DISPLAY 0.872340 (-3025 5600);
PAINT GREEN (-3025 5600);
DISPLAY INVISIBLE (-3025 5600);
FORCEPROP 1 LAST HDL_TAP TRUE
J 0
(-2700 5425);
DISPLAY 0.872340 (-2700 5425);
DISPLAY INVISIBLE (-2700 5425);
FORCEPROP 1 LAST PATH I696
J 0
(-3027 5550);
DISPLAY 0.872340 (-3027 5550);
PAINT GREEN (-3027 5550);
DISPLAY INVISIBLE (-3027 5550);
FORCEADD TAP..1
(-3025 5350);
FORCEPROP 3 LASTPIN (-3075 5350) SIG_NAME M_A_CPU0_SA_DQ<14>
J 0
(-3065 5360);
DISPLAY 0.659574 (-3065 5360);
PAINT MONO (-3065 5360);
DISPLAY INVISIBLE (-3065 5360);
FORCEPROP 1 LASTPIN (-3075 5350) BN 14
J 0
(-3087 5358);
DISPLAY 0.489362 (-3087 5358);
PAINT MONO (-3087 5358);
FORCEPROP 2 LAST CDS_LIB mstr_standard
J 0
(-3025 5350);
DISPLAY INVISIBLE (-3025 5350);
FORCEPROP 1 LAST BODY_TYPE PLUMBING
J 0
(-3025 5400);
DISPLAY 0.872340 (-3025 5400);
PAINT GREEN (-3025 5400);
DISPLAY INVISIBLE (-3025 5400);
FORCEPROP 1 LAST HDL_TAP TRUE
J 0
(-2700 5225);
DISPLAY 0.872340 (-2700 5225);
DISPLAY INVISIBLE (-2700 5225);
FORCEPROP 1 LAST PATH I697
J 0
(-3027 5350);
DISPLAY 0.872340 (-3027 5350);
PAINT GREEN (-3027 5350);
DISPLAY INVISIBLE (-3027 5350);
FORCEADD TAP..1
(-3025 5200);
FORCEPROP 3 LASTPIN (-3075 5200) SIG_NAME M_A_CPU0_SA_DQ<16>
J 0
(-3065 5210);
DISPLAY 0.659574 (-3065 5210);
PAINT MONO (-3065 5210);
DISPLAY INVISIBLE (-3065 5210);
FORCEPROP 1 LASTPIN (-3075 5200) BN 16
J 0
(-3087 5208);
DISPLAY 0.489362 (-3087 5208);
PAINT MONO (-3087 5208);
FORCEPROP 2 LAST CDS_LIB mstr_standard
J 0
(-3025 5200);
DISPLAY INVISIBLE (-3025 5200);
FORCEPROP 1 LAST BODY_TYPE PLUMBING
J 0
(-3025 5250);
DISPLAY 0.872340 (-3025 5250);
PAINT GREEN (-3025 5250);
DISPLAY INVISIBLE (-3025 5250);
FORCEPROP 1 LAST HDL_TAP TRUE
J 0
(-2700 5075);
DISPLAY 0.872340 (-2700 5075);
DISPLAY INVISIBLE (-2700 5075);
FORCEPROP 1 LAST PATH I698
J 0
(-3027 5200);
DISPLAY 0.872340 (-3027 5200);
PAINT GREEN (-3027 5200);
DISPLAY INVISIBLE (-3027 5200);
FORCEADD TAP..1
(-3025 5150);
FORCEPROP 3 LASTPIN (-3075 5150) SIG_NAME M_A_CPU0_SA_DQ<17>
J 0
(-3065 5160);
DISPLAY 0.659574 (-3065 5160);
PAINT MONO (-3065 5160);
DISPLAY INVISIBLE (-3065 5160);
FORCEPROP 1 LASTPIN (-3075 5150) BN 17
J 0
(-3087 5158);
DISPLAY 0.489362 (-3087 5158);
PAINT MONO (-3087 5158);
FORCEPROP 2 LAST CDS_LIB mstr_standard
J 0
(-3025 5150);
DISPLAY INVISIBLE (-3025 5150);
FORCEPROP 1 LAST BODY_TYPE PLUMBING
J 0
(-3025 5200);
DISPLAY 0.872340 (-3025 5200);
PAINT GREEN (-3025 5200);
DISPLAY INVISIBLE (-3025 5200);
FORCEPROP 1 LAST HDL_TAP TRUE
J 0
(-2700 5025);
DISPLAY 0.872340 (-2700 5025);
DISPLAY INVISIBLE (-2700 5025);
FORCEPROP 1 LAST PATH I699
J 0
(-3027 5150);
DISPLAY 0.872340 (-3027 5150);
PAINT GREEN (-3027 5150);
DISPLAY INVISIBLE (-3027 5150);
FORCEADD TAP..1
(-3025 5300);
FORCEPROP 3 LASTPIN (-3075 5300) SIG_NAME M_A_CPU0_SA_DQ<15>
J 0
(-3065 5310);
DISPLAY 0.659574 (-3065 5310);
PAINT MONO (-3065 5310);
DISPLAY INVISIBLE (-3065 5310);
FORCEPROP 1 LASTPIN (-3075 5300) BN 15
J 0
(-3087 5308);
DISPLAY 0.489362 (-3087 5308);
PAINT MONO (-3087 5308);
FORCEPROP 2 LAST CDS_LIB mstr_standard
J 0
(-3025 5300);
DISPLAY INVISIBLE (-3025 5300);
FORCEPROP 1 LAST BODY_TYPE PLUMBING
J 0
(-3025 5350);
DISPLAY 0.872340 (-3025 5350);
PAINT GREEN (-3025 5350);
DISPLAY INVISIBLE (-3025 5350);
FORCEPROP 1 LAST HDL_TAP TRUE
J 0
(-2700 5175);
DISPLAY 0.872340 (-2700 5175);
DISPLAY INVISIBLE (-2700 5175);
FORCEPROP 1 LAST PATH I700
J 0
(-3027 5300);
DISPLAY 0.872340 (-3027 5300);
PAINT GREEN (-3027 5300);
DISPLAY INVISIBLE (-3027 5300);
FORCEADD TAP..1
(-3025 5050);
FORCEPROP 3 LASTPIN (-3075 5050) SIG_NAME M_A_CPU0_SA_DQ<19>
J 0
(-3065 5060);
DISPLAY 0.659574 (-3065 5060);
PAINT MONO (-3065 5060);
DISPLAY INVISIBLE (-3065 5060);
FORCEPROP 1 LASTPIN (-3075 5050) BN 19
J 0
(-3087 5058);
DISPLAY 0.489362 (-3087 5058);
PAINT MONO (-3087 5058);
FORCEPROP 2 LAST CDS_LIB mstr_standard
J 0
(-3025 5050);
DISPLAY INVISIBLE (-3025 5050);
FORCEPROP 1 LAST BODY_TYPE PLUMBING
J 0
(-3025 5100);
DISPLAY 0.872340 (-3025 5100);
PAINT GREEN (-3025 5100);
DISPLAY INVISIBLE (-3025 5100);
FORCEPROP 1 LAST HDL_TAP TRUE
J 0
(-2700 4925);
DISPLAY 0.872340 (-2700 4925);
DISPLAY INVISIBLE (-2700 4925);
FORCEPROP 1 LAST PATH I701
J 0
(-3027 5050);
DISPLAY 0.872340 (-3027 5050);
PAINT GREEN (-3027 5050);
DISPLAY INVISIBLE (-3027 5050);
FORCEADD TAP..1
(-3025 5100);
FORCEPROP 3 LASTPIN (-3075 5100) SIG_NAME M_A_CPU0_SA_DQ<18>
J 0
(-3065 5110);
DISPLAY 0.659574 (-3065 5110);
PAINT MONO (-3065 5110);
DISPLAY INVISIBLE (-3065 5110);
FORCEPROP 1 LASTPIN (-3075 5100) BN 18
J 0
(-3087 5108);
DISPLAY 0.489362 (-3087 5108);
PAINT MONO (-3087 5108);
FORCEPROP 2 LAST CDS_LIB mstr_standard
J 0
(-3025 5100);
DISPLAY INVISIBLE (-3025 5100);
FORCEPROP 1 LAST BODY_TYPE PLUMBING
J 0
(-3025 5150);
DISPLAY 0.872340 (-3025 5150);
PAINT GREEN (-3025 5150);
DISPLAY INVISIBLE (-3025 5150);
FORCEPROP 1 LAST HDL_TAP TRUE
J 0
(-2700 4975);
DISPLAY 0.872340 (-2700 4975);
DISPLAY INVISIBLE (-2700 4975);
FORCEPROP 1 LAST PATH I702
J 0
(-3027 5100);
DISPLAY 0.872340 (-3027 5100);
PAINT GREEN (-3027 5100);
DISPLAY INVISIBLE (-3027 5100);
FORCEADD OFFPAGE..3
(-2300 4325);
FORCEPROP 2 LAST $XR0 86 
J 0
(-2086 4325);
DISPLAY 0.638298 (-2086 4325);
PAINT MONO (-2086 4325);
FORCEPROP 2 LAST CDS_LIB mstr_standard
J 0
(-2300 4325);
DISPLAY INVISIBLE (-2300 4325);
FORCEPROP 1 LAST OFFPAGE TRUE
J 0
(-1975 4200);
DISPLAY 0.872340 (-1975 4200);
PAINT GREEN (-1975 4200);
DISPLAY INVISIBLE (-1975 4200);
FORCEPROP 1 LAST COMMENT_BODY TRUE
J 0
(-2350 4225);
DISPLAY 0.872340 (-2350 4225);
PAINT GREEN (-2350 4225);
DISPLAY INVISIBLE (-2350 4225);
FORCEPROP 2 LAST PATH I703
J 0
(-2075 4375);
DISPLAY 1.021277 (-2075 4375);
DISPLAY INVISIBLE (-2075 4375);
FORCEADD TAP..1
(-3025 4950);
FORCEPROP 3 LASTPIN (-3075 4950) SIG_NAME M_A_CPU0_SA_DQ<21>
J 0
(-3065 4960);
DISPLAY 0.659574 (-3065 4960);
PAINT MONO (-3065 4960);
DISPLAY INVISIBLE (-3065 4960);
FORCEPROP 1 LASTPIN (-3075 4950) BN 21
J 0
(-3087 4958);
DISPLAY 0.489362 (-3087 4958);
PAINT MONO (-3087 4958);
FORCEPROP 2 LAST CDS_LIB mstr_standard
J 0
(-3025 4950);
DISPLAY INVISIBLE (-3025 4950);
FORCEPROP 1 LAST BODY_TYPE PLUMBING
J 0
(-3025 5000);
DISPLAY 0.872340 (-3025 5000);
PAINT GREEN (-3025 5000);
DISPLAY INVISIBLE (-3025 5000);
FORCEPROP 1 LAST HDL_TAP TRUE
J 0
(-2700 4825);
DISPLAY 0.872340 (-2700 4825);
DISPLAY INVISIBLE (-2700 4825);
FORCEPROP 1 LAST PATH I704
J 0
(-3027 4950);
DISPLAY 0.872340 (-3027 4950);
PAINT GREEN (-3027 4950);
DISPLAY INVISIBLE (-3027 4950);
FORCEADD TAP..1
(-3025 4900);
FORCEPROP 3 LASTPIN (-3075 4900) SIG_NAME M_A_CPU0_SA_DQ<22>
J 0
(-3065 4910);
DISPLAY 0.659574 (-3065 4910);
PAINT MONO (-3065 4910);
DISPLAY INVISIBLE (-3065 4910);
FORCEPROP 1 LASTPIN (-3075 4900) BN 22
J 0
(-3087 4908);
DISPLAY 0.489362 (-3087 4908);
PAINT MONO (-3087 4908);
FORCEPROP 2 LAST CDS_LIB mstr_standard
J 0
(-3025 4900);
DISPLAY INVISIBLE (-3025 4900);
FORCEPROP 1 LAST BODY_TYPE PLUMBING
J 0
(-3025 4950);
DISPLAY 0.872340 (-3025 4950);
PAINT GREEN (-3025 4950);
DISPLAY INVISIBLE (-3025 4950);
FORCEPROP 1 LAST HDL_TAP TRUE
J 0
(-2700 4775);
DISPLAY 0.872340 (-2700 4775);
DISPLAY INVISIBLE (-2700 4775);
FORCEPROP 1 LAST PATH I705
J 0
(-3027 4900);
DISPLAY 0.872340 (-3027 4900);
PAINT GREEN (-3027 4900);
DISPLAY INVISIBLE (-3027 4900);
FORCEADD TAP..1
(-3025 5000);
FORCEPROP 3 LASTPIN (-3075 5000) SIG_NAME M_A_CPU0_SA_DQ<20>
J 0
(-3065 5010);
DISPLAY 0.659574 (-3065 5010);
PAINT MONO (-3065 5010);
DISPLAY INVISIBLE (-3065 5010);
FORCEPROP 1 LASTPIN (-3075 5000) BN 20
J 0
(-3087 5008);
DISPLAY 0.489362 (-3087 5008);
PAINT MONO (-3087 5008);
FORCEPROP 2 LAST CDS_LIB mstr_standard
J 0
(-3025 5000);
DISPLAY INVISIBLE (-3025 5000);
FORCEPROP 1 LAST BODY_TYPE PLUMBING
J 0
(-3025 5050);
DISPLAY 0.872340 (-3025 5050);
PAINT GREEN (-3025 5050);
DISPLAY INVISIBLE (-3025 5050);
FORCEPROP 1 LAST HDL_TAP TRUE
J 0
(-2700 4875);
DISPLAY 0.872340 (-2700 4875);
DISPLAY INVISIBLE (-2700 4875);
FORCEPROP 1 LAST PATH I706
J 0
(-3027 5000);
DISPLAY 0.872340 (-3027 5000);
PAINT GREEN (-3027 5000);
DISPLAY INVISIBLE (-3027 5000);
FORCEADD TAP..1
(-3025 4850);
FORCEPROP 3 LASTPIN (-3075 4850) SIG_NAME M_A_CPU0_SA_DQ<23>
J 0
(-3065 4860);
DISPLAY 0.659574 (-3065 4860);
PAINT MONO (-3065 4860);
DISPLAY INVISIBLE (-3065 4860);
FORCEPROP 1 LASTPIN (-3075 4850) BN 23
J 0
(-3087 4858);
DISPLAY 0.489362 (-3087 4858);
PAINT MONO (-3087 4858);
FORCEPROP 2 LAST CDS_LIB mstr_standard
J 0
(-3025 4850);
DISPLAY INVISIBLE (-3025 4850);
FORCEPROP 1 LAST BODY_TYPE PLUMBING
J 0
(-3025 4900);
DISPLAY 0.872340 (-3025 4900);
PAINT GREEN (-3025 4900);
DISPLAY INVISIBLE (-3025 4900);
FORCEPROP 1 LAST HDL_TAP TRUE
J 0
(-2700 4725);
DISPLAY 0.872340 (-2700 4725);
DISPLAY INVISIBLE (-2700 4725);
FORCEPROP 1 LAST PATH I707
J 0
(-3027 4850);
DISPLAY 0.872340 (-3027 4850);
PAINT GREEN (-3027 4850);
DISPLAY INVISIBLE (-3027 4850);
FORCEADD TAP..1
(-3025 4650);
FORCEPROP 3 LASTPIN (-3075 4650) SIG_NAME M_A_CPU0_SA_DQ<26>
J 0
(-3065 4660);
DISPLAY 0.659574 (-3065 4660);
PAINT MONO (-3065 4660);
DISPLAY INVISIBLE (-3065 4660);
FORCEPROP 1 LASTPIN (-3075 4650) BN 26
J 0
(-3087 4658);
DISPLAY 0.489362 (-3087 4658);
PAINT MONO (-3087 4658);
FORCEPROP 2 LAST CDS_LIB mstr_standard
J 0
(-3025 4650);
DISPLAY INVISIBLE (-3025 4650);
FORCEPROP 1 LAST BODY_TYPE PLUMBING
J 0
(-3025 4700);
DISPLAY 0.872340 (-3025 4700);
PAINT GREEN (-3025 4700);
DISPLAY INVISIBLE (-3025 4700);
FORCEPROP 1 LAST HDL_TAP TRUE
J 0
(-2700 4525);
DISPLAY 0.872340 (-2700 4525);
DISPLAY INVISIBLE (-2700 4525);
FORCEPROP 1 LAST PATH I708
J 0
(-3027 4650);
DISPLAY 0.872340 (-3027 4650);
PAINT GREEN (-3027 4650);
DISPLAY INVISIBLE (-3027 4650);
FORCEADD TAP..1
(-3025 4700);
FORCEPROP 3 LASTPIN (-3075 4700) SIG_NAME M_A_CPU0_SA_DQ<25>
J 0
(-3065 4710);
DISPLAY 0.659574 (-3065 4710);
PAINT MONO (-3065 4710);
DISPLAY INVISIBLE (-3065 4710);
FORCEPROP 1 LASTPIN (-3075 4700) BN 25
J 0
(-3087 4708);
DISPLAY 0.489362 (-3087 4708);
PAINT MONO (-3087 4708);
FORCEPROP 2 LAST CDS_LIB mstr_standard
J 0
(-3025 4700);
DISPLAY INVISIBLE (-3025 4700);
FORCEPROP 1 LAST BODY_TYPE PLUMBING
J 0
(-3025 4750);
DISPLAY 0.872340 (-3025 4750);
PAINT GREEN (-3025 4750);
DISPLAY INVISIBLE (-3025 4750);
FORCEPROP 1 LAST HDL_TAP TRUE
J 0
(-2700 4575);
DISPLAY 0.872340 (-2700 4575);
DISPLAY INVISIBLE (-2700 4575);
FORCEPROP 1 LAST PATH I709
J 0
(-3027 4700);
DISPLAY 0.872340 (-3027 4700);
PAINT GREEN (-3027 4700);
DISPLAY INVISIBLE (-3027 4700);
FORCEADD TAP..1
(-3025 4750);
FORCEPROP 3 LASTPIN (-3075 4750) SIG_NAME M_A_CPU0_SA_DQ<24>
J 0
(-3065 4760);
DISPLAY 0.659574 (-3065 4760);
PAINT MONO (-3065 4760);
DISPLAY INVISIBLE (-3065 4760);
FORCEPROP 1 LASTPIN (-3075 4750) BN 24
J 0
(-3087 4758);
DISPLAY 0.489362 (-3087 4758);
PAINT MONO (-3087 4758);
FORCEPROP 2 LAST CDS_LIB mstr_standard
J 0
(-3025 4750);
DISPLAY INVISIBLE (-3025 4750);
FORCEPROP 1 LAST BODY_TYPE PLUMBING
J 0
(-3025 4800);
DISPLAY 0.872340 (-3025 4800);
PAINT GREEN (-3025 4800);
DISPLAY INVISIBLE (-3025 4800);
FORCEPROP 1 LAST HDL_TAP TRUE
J 0
(-2700 4625);
DISPLAY 0.872340 (-2700 4625);
DISPLAY INVISIBLE (-2700 4625);
FORCEPROP 1 LAST PATH I710
J 0
(-3027 4750);
DISPLAY 0.872340 (-3027 4750);
PAINT GREEN (-3027 4750);
DISPLAY INVISIBLE (-3027 4750);
FORCEADD TAP..1
(-3025 4550);
FORCEPROP 3 LASTPIN (-3075 4550) SIG_NAME M_A_CPU0_SA_DQ<28>
J 0
(-3065 4560);
DISPLAY 0.659574 (-3065 4560);
PAINT MONO (-3065 4560);
DISPLAY INVISIBLE (-3065 4560);
FORCEPROP 1 LASTPIN (-3075 4550) BN 28
J 0
(-3087 4558);
DISPLAY 0.489362 (-3087 4558);
PAINT MONO (-3087 4558);
FORCEPROP 2 LAST CDS_LIB mstr_standard
J 0
(-3025 4550);
DISPLAY INVISIBLE (-3025 4550);
FORCEPROP 1 LAST BODY_TYPE PLUMBING
J 0
(-3025 4600);
DISPLAY 0.872340 (-3025 4600);
PAINT GREEN (-3025 4600);
DISPLAY INVISIBLE (-3025 4600);
FORCEPROP 1 LAST HDL_TAP TRUE
J 0
(-2700 4425);
DISPLAY 0.872340 (-2700 4425);
DISPLAY INVISIBLE (-2700 4425);
FORCEPROP 1 LAST PATH I711
J 0
(-3027 4550);
DISPLAY 0.872340 (-3027 4550);
PAINT GREEN (-3027 4550);
DISPLAY INVISIBLE (-3027 4550);
FORCEADD TAP..1
(-3025 4600);
FORCEPROP 3 LASTPIN (-3075 4600) SIG_NAME M_A_CPU0_SA_DQ<27>
J 0
(-3065 4610);
DISPLAY 0.659574 (-3065 4610);
PAINT MONO (-3065 4610);
DISPLAY INVISIBLE (-3065 4610);
FORCEPROP 1 LASTPIN (-3075 4600) BN 27
J 0
(-3087 4608);
DISPLAY 0.489362 (-3087 4608);
PAINT MONO (-3087 4608);
FORCEPROP 2 LAST CDS_LIB mstr_standard
J 0
(-3025 4600);
DISPLAY INVISIBLE (-3025 4600);
FORCEPROP 1 LAST BODY_TYPE PLUMBING
J 0
(-3025 4650);
DISPLAY 0.872340 (-3025 4650);
PAINT GREEN (-3025 4650);
DISPLAY INVISIBLE (-3025 4650);
FORCEPROP 1 LAST HDL_TAP TRUE
J 0
(-2700 4475);
DISPLAY 0.872340 (-2700 4475);
DISPLAY INVISIBLE (-2700 4475);
FORCEPROP 1 LAST PATH I712
J 0
(-3027 4600);
DISPLAY 0.872340 (-3027 4600);
PAINT GREEN (-3027 4600);
DISPLAY INVISIBLE (-3027 4600);
FORCEADD TAP..1
(-3025 4400);
FORCEPROP 3 LASTPIN (-3075 4400) SIG_NAME M_A_CPU0_SA_DQ<31>
J 0
(-3065 4410);
DISPLAY 0.659574 (-3065 4410);
PAINT MONO (-3065 4410);
DISPLAY INVISIBLE (-3065 4410);
FORCEPROP 1 LASTPIN (-3075 4400) BN 31
J 0
(-3087 4408);
DISPLAY 0.489362 (-3087 4408);
PAINT MONO (-3087 4408);
FORCEPROP 2 LAST CDS_LIB mstr_standard
J 0
(-3025 4400);
DISPLAY INVISIBLE (-3025 4400);
FORCEPROP 1 LAST BODY_TYPE PLUMBING
J 0
(-3025 4450);
DISPLAY 0.872340 (-3025 4450);
PAINT GREEN (-3025 4450);
DISPLAY INVISIBLE (-3025 4450);
FORCEPROP 1 LAST HDL_TAP TRUE
J 0
(-2700 4275);
DISPLAY 0.872340 (-2700 4275);
DISPLAY INVISIBLE (-2700 4275);
FORCEPROP 1 LAST PATH I713
J 0
(-3027 4400);
DISPLAY 0.872340 (-3027 4400);
PAINT GREEN (-3027 4400);
DISPLAY INVISIBLE (-3027 4400);
FORCEADD TAP..1
(-3025 4450);
FORCEPROP 3 LASTPIN (-3075 4450) SIG_NAME M_A_CPU0_SA_DQ<30>
J 0
(-3065 4460);
DISPLAY 0.659574 (-3065 4460);
PAINT MONO (-3065 4460);
DISPLAY INVISIBLE (-3065 4460);
FORCEPROP 1 LASTPIN (-3075 4450) BN 30
J 0
(-3087 4458);
DISPLAY 0.489362 (-3087 4458);
PAINT MONO (-3087 4458);
FORCEPROP 2 LAST CDS_LIB mstr_standard
J 0
(-3025 4450);
DISPLAY INVISIBLE (-3025 4450);
FORCEPROP 1 LAST BODY_TYPE PLUMBING
J 0
(-3025 4500);
DISPLAY 0.872340 (-3025 4500);
PAINT GREEN (-3025 4500);
DISPLAY INVISIBLE (-3025 4500);
FORCEPROP 1 LAST HDL_TAP TRUE
J 0
(-2700 4325);
DISPLAY 0.872340 (-2700 4325);
DISPLAY INVISIBLE (-2700 4325);
FORCEPROP 1 LAST PATH I714
J 0
(-3027 4450);
DISPLAY 0.872340 (-3027 4450);
PAINT GREEN (-3027 4450);
DISPLAY INVISIBLE (-3027 4450);
FORCEADD TAP..1
(-3025 4500);
FORCEPROP 3 LASTPIN (-3075 4500) SIG_NAME M_A_CPU0_SA_DQ<29>
J 0
(-3065 4510);
DISPLAY 0.659574 (-3065 4510);
PAINT MONO (-3065 4510);
DISPLAY INVISIBLE (-3065 4510);
FORCEPROP 1 LASTPIN (-3075 4500) BN 29
J 0
(-3087 4508);
DISPLAY 0.489362 (-3087 4508);
PAINT MONO (-3087 4508);
FORCEPROP 2 LAST CDS_LIB mstr_standard
J 0
(-3025 4500);
DISPLAY INVISIBLE (-3025 4500);
FORCEPROP 1 LAST BODY_TYPE PLUMBING
J 0
(-3025 4550);
DISPLAY 0.872340 (-3025 4550);
PAINT GREEN (-3025 4550);
DISPLAY INVISIBLE (-3025 4550);
FORCEPROP 1 LAST HDL_TAP TRUE
J 0
(-2700 4375);
DISPLAY 0.872340 (-2700 4375);
DISPLAY INVISIBLE (-2700 4375);
FORCEPROP 1 LAST PATH I715
J 0
(-3027 4500);
DISPLAY 0.872340 (-3027 4500);
PAINT GREEN (-3027 4500);
DISPLAY INVISIBLE (-3027 4500);
FORCEADD TAP..1
(-3025 4300);
FORCEPROP 3 LASTPIN (-3075 4300) SIG_NAME M_A_CPU0_SB_DQ<0>
J 0
(-3065 4310);
DISPLAY 0.659574 (-3065 4310);
PAINT MONO (-3065 4310);
DISPLAY INVISIBLE (-3065 4310);
FORCEPROP 1 LASTPIN (-3075 4300) BN 0
J 0
(-3087 4308);
DISPLAY 0.489362 (-3087 4308);
PAINT MONO (-3087 4308);
FORCEPROP 2 LAST CDS_LIB mstr_standard
J 0
(-3025 4300);
DISPLAY INVISIBLE (-3025 4300);
FORCEPROP 1 LAST BODY_TYPE PLUMBING
J 0
(-3025 4350);
DISPLAY 0.872340 (-3025 4350);
PAINT GREEN (-3025 4350);
DISPLAY INVISIBLE (-3025 4350);
FORCEPROP 1 LAST HDL_TAP TRUE
J 0
(-2700 4175);
DISPLAY 0.872340 (-2700 4175);
DISPLAY INVISIBLE (-2700 4175);
FORCEPROP 1 LAST PATH I716
J 0
(-3027 4300);
DISPLAY 0.872340 (-3027 4300);
PAINT GREEN (-3027 4300);
DISPLAY INVISIBLE (-3027 4300);
FORCEADD TAP..1
(-3025 4150);
FORCEPROP 3 LASTPIN (-3075 4150) SIG_NAME M_A_CPU0_SB_DQ<3>
J 0
(-3065 4160);
DISPLAY 0.659574 (-3065 4160);
PAINT MONO (-3065 4160);
DISPLAY INVISIBLE (-3065 4160);
FORCEPROP 1 LASTPIN (-3075 4150) BN 3
J 0
(-3087 4158);
DISPLAY 0.489362 (-3087 4158);
PAINT MONO (-3087 4158);
FORCEPROP 2 LAST CDS_LIB mstr_standard
J 0
(-3025 4150);
DISPLAY INVISIBLE (-3025 4150);
FORCEPROP 1 LAST BODY_TYPE PLUMBING
J 0
(-3025 4200);
DISPLAY 0.872340 (-3025 4200);
PAINT GREEN (-3025 4200);
DISPLAY INVISIBLE (-3025 4200);
FORCEPROP 1 LAST HDL_TAP TRUE
J 0
(-2700 4025);
DISPLAY 0.872340 (-2700 4025);
DISPLAY INVISIBLE (-2700 4025);
FORCEPROP 1 LAST PATH I717
J 0
(-3027 4150);
DISPLAY 0.872340 (-3027 4150);
PAINT GREEN (-3027 4150);
DISPLAY INVISIBLE (-3027 4150);
FORCEADD TAP..1
(-3025 4200);
FORCEPROP 3 LASTPIN (-3075 4200) SIG_NAME M_A_CPU0_SB_DQ<2>
J 0
(-3065 4210);
DISPLAY 0.659574 (-3065 4210);
PAINT MONO (-3065 4210);
DISPLAY INVISIBLE (-3065 4210);
FORCEPROP 1 LASTPIN (-3075 4200) BN 2
J 0
(-3087 4208);
DISPLAY 0.489362 (-3087 4208);
PAINT MONO (-3087 4208);
FORCEPROP 2 LAST CDS_LIB mstr_standard
J 0
(-3025 4200);
DISPLAY INVISIBLE (-3025 4200);
FORCEPROP 1 LAST BODY_TYPE PLUMBING
J 0
(-3025 4250);
DISPLAY 0.872340 (-3025 4250);
PAINT GREEN (-3025 4250);
DISPLAY INVISIBLE (-3025 4250);
FORCEPROP 1 LAST HDL_TAP TRUE
J 0
(-2700 4075);
DISPLAY 0.872340 (-2700 4075);
DISPLAY INVISIBLE (-2700 4075);
FORCEPROP 1 LAST PATH I718
J 0
(-3027 4200);
DISPLAY 0.872340 (-3027 4200);
PAINT GREEN (-3027 4200);
DISPLAY INVISIBLE (-3027 4200);
FORCEADD TAP..1
(-3025 4250);
FORCEPROP 3 LASTPIN (-3075 4250) SIG_NAME M_A_CPU0_SB_DQ<1>
J 0
(-3065 4260);
DISPLAY 0.659574 (-3065 4260);
PAINT MONO (-3065 4260);
DISPLAY INVISIBLE (-3065 4260);
FORCEPROP 1 LASTPIN (-3075 4250) BN 1
J 0
(-3087 4258);
DISPLAY 0.489362 (-3087 4258);
PAINT MONO (-3087 4258);
FORCEPROP 2 LAST CDS_LIB mstr_standard
J 0
(-3025 4250);
DISPLAY INVISIBLE (-3025 4250);
FORCEPROP 1 LAST BODY_TYPE PLUMBING
J 0
(-3025 4300);
DISPLAY 0.872340 (-3025 4300);
PAINT GREEN (-3025 4300);
DISPLAY INVISIBLE (-3025 4300);
FORCEPROP 1 LAST HDL_TAP TRUE
J 0
(-2700 4125);
DISPLAY 0.872340 (-2700 4125);
DISPLAY INVISIBLE (-2700 4125);
FORCEPROP 1 LAST PATH I719
J 0
(-3027 4250);
DISPLAY 0.872340 (-3027 4250);
PAINT GREEN (-3027 4250);
DISPLAY INVISIBLE (-3027 4250);
FORCEADD TAP..1
(-3025 4100);
FORCEPROP 3 LASTPIN (-3075 4100) SIG_NAME M_A_CPU0_SB_DQ<4>
J 0
(-3065 4110);
DISPLAY 0.659574 (-3065 4110);
PAINT MONO (-3065 4110);
DISPLAY INVISIBLE (-3065 4110);
FORCEPROP 1 LASTPIN (-3075 4100) BN 4
J 0
(-3087 4108);
DISPLAY 0.489362 (-3087 4108);
PAINT MONO (-3087 4108);
FORCEPROP 2 LAST CDS_LIB mstr_standard
J 0
(-3025 4100);
DISPLAY INVISIBLE (-3025 4100);
FORCEPROP 1 LAST BODY_TYPE PLUMBING
J 0
(-3025 4150);
DISPLAY 0.872340 (-3025 4150);
PAINT GREEN (-3025 4150);
DISPLAY INVISIBLE (-3025 4150);
FORCEPROP 1 LAST HDL_TAP TRUE
J 0
(-2700 3975);
DISPLAY 0.872340 (-2700 3975);
DISPLAY INVISIBLE (-2700 3975);
FORCEPROP 1 LAST PATH I720
J 0
(-3027 4100);
DISPLAY 0.872340 (-3027 4100);
PAINT GREEN (-3027 4100);
DISPLAY INVISIBLE (-3027 4100);
FORCEADD TAP..1
(-3025 4050);
FORCEPROP 3 LASTPIN (-3075 4050) SIG_NAME M_A_CPU0_SB_DQ<5>
J 0
(-3065 4060);
DISPLAY 0.659574 (-3065 4060);
PAINT MONO (-3065 4060);
DISPLAY INVISIBLE (-3065 4060);
FORCEPROP 1 LASTPIN (-3075 4050) BN 5
J 0
(-3087 4058);
DISPLAY 0.489362 (-3087 4058);
PAINT MONO (-3087 4058);
FORCEPROP 2 LAST CDS_LIB mstr_standard
J 0
(-3025 4050);
DISPLAY INVISIBLE (-3025 4050);
FORCEPROP 1 LAST BODY_TYPE PLUMBING
J 0
(-3025 4100);
DISPLAY 0.872340 (-3025 4100);
PAINT GREEN (-3025 4100);
DISPLAY INVISIBLE (-3025 4100);
FORCEPROP 1 LAST HDL_TAP TRUE
J 0
(-2700 3925);
DISPLAY 0.872340 (-2700 3925);
DISPLAY INVISIBLE (-2700 3925);
FORCEPROP 1 LAST PATH I721
J 0
(-3027 4050);
DISPLAY 0.872340 (-3027 4050);
PAINT GREEN (-3027 4050);
DISPLAY INVISIBLE (-3027 4050);
FORCEADD TAP..1
(-3025 3850);
FORCEPROP 3 LASTPIN (-3075 3850) SIG_NAME M_A_CPU0_SB_DQ<8>
J 0
(-3065 3860);
DISPLAY 0.659574 (-3065 3860);
PAINT MONO (-3065 3860);
DISPLAY INVISIBLE (-3065 3860);
FORCEPROP 1 LASTPIN (-3075 3850) BN 8
J 0
(-3087 3858);
DISPLAY 0.489362 (-3087 3858);
PAINT MONO (-3087 3858);
FORCEPROP 2 LAST CDS_LIB mstr_standard
J 0
(-3025 3850);
DISPLAY INVISIBLE (-3025 3850);
FORCEPROP 1 LAST BODY_TYPE PLUMBING
J 0
(-3025 3900);
DISPLAY 0.872340 (-3025 3900);
PAINT GREEN (-3025 3900);
DISPLAY INVISIBLE (-3025 3900);
FORCEPROP 1 LAST HDL_TAP TRUE
J 0
(-2700 3725);
DISPLAY 0.872340 (-2700 3725);
DISPLAY INVISIBLE (-2700 3725);
FORCEPROP 1 LAST PATH I722
J 0
(-3027 3850);
DISPLAY 0.872340 (-3027 3850);
PAINT GREEN (-3027 3850);
DISPLAY INVISIBLE (-3027 3850);
FORCEADD TAP..1
(-3025 3950);
FORCEPROP 3 LASTPIN (-3075 3950) SIG_NAME M_A_CPU0_SB_DQ<7>
J 0
(-3065 3960);
DISPLAY 0.659574 (-3065 3960);
PAINT MONO (-3065 3960);
DISPLAY INVISIBLE (-3065 3960);
FORCEPROP 1 LASTPIN (-3075 3950) BN 7
J 0
(-3087 3958);
DISPLAY 0.489362 (-3087 3958);
PAINT MONO (-3087 3958);
FORCEPROP 2 LAST CDS_LIB mstr_standard
J 0
(-3025 3950);
DISPLAY INVISIBLE (-3025 3950);
FORCEPROP 1 LAST BODY_TYPE PLUMBING
J 0
(-3025 4000);
DISPLAY 0.872340 (-3025 4000);
PAINT GREEN (-3025 4000);
DISPLAY INVISIBLE (-3025 4000);
FORCEPROP 1 LAST HDL_TAP TRUE
J 0
(-2700 3825);
DISPLAY 0.872340 (-2700 3825);
DISPLAY INVISIBLE (-2700 3825);
FORCEPROP 1 LAST PATH I723
J 0
(-3027 3950);
DISPLAY 0.872340 (-3027 3950);
PAINT GREEN (-3027 3950);
DISPLAY INVISIBLE (-3027 3950);
FORCEADD TAP..1
(-3025 4000);
FORCEPROP 3 LASTPIN (-3075 4000) SIG_NAME M_A_CPU0_SB_DQ<6>
J 0
(-3065 4010);
DISPLAY 0.659574 (-3065 4010);
PAINT MONO (-3065 4010);
DISPLAY INVISIBLE (-3065 4010);
FORCEPROP 1 LASTPIN (-3075 4000) BN 6
J 0
(-3087 4008);
DISPLAY 0.489362 (-3087 4008);
PAINT MONO (-3087 4008);
FORCEPROP 2 LAST CDS_LIB mstr_standard
J 0
(-3025 4000);
DISPLAY INVISIBLE (-3025 4000);
FORCEPROP 1 LAST BODY_TYPE PLUMBING
J 0
(-3025 4050);
DISPLAY 0.872340 (-3025 4050);
PAINT GREEN (-3025 4050);
DISPLAY INVISIBLE (-3025 4050);
FORCEPROP 1 LAST HDL_TAP TRUE
J 0
(-2700 3875);
DISPLAY 0.872340 (-2700 3875);
DISPLAY INVISIBLE (-2700 3875);
FORCEPROP 1 LAST PATH I724
J 0
(-3027 4000);
DISPLAY 0.872340 (-3027 4000);
PAINT GREEN (-3027 4000);
DISPLAY INVISIBLE (-3027 4000);
FORCEADD TAP..1
(-3025 3800);
FORCEPROP 3 LASTPIN (-3075 3800) SIG_NAME M_A_CPU0_SB_DQ<9>
J 0
(-3065 3810);
DISPLAY 0.659574 (-3065 3810);
PAINT MONO (-3065 3810);
DISPLAY INVISIBLE (-3065 3810);
FORCEPROP 1 LASTPIN (-3075 3800) BN 9
J 0
(-3087 3808);
DISPLAY 0.489362 (-3087 3808);
PAINT MONO (-3087 3808);
FORCEPROP 2 LAST CDS_LIB mstr_standard
J 0
(-3025 3800);
DISPLAY INVISIBLE (-3025 3800);
FORCEPROP 1 LAST BODY_TYPE PLUMBING
J 0
(-3025 3850);
DISPLAY 0.872340 (-3025 3850);
PAINT GREEN (-3025 3850);
DISPLAY INVISIBLE (-3025 3850);
FORCEPROP 1 LAST HDL_TAP TRUE
J 0
(-2700 3675);
DISPLAY 0.872340 (-2700 3675);
DISPLAY INVISIBLE (-2700 3675);
FORCEPROP 1 LAST PATH I725
J 0
(-3027 3800);
DISPLAY 0.872340 (-3027 3800);
PAINT GREEN (-3027 3800);
DISPLAY INVISIBLE (-3027 3800);
FORCEADD TAP..1
(-3025 3600);
FORCEPROP 3 LASTPIN (-3075 3600) SIG_NAME M_A_CPU0_SB_DQ<13>
J 0
(-3065 3610);
DISPLAY 0.659574 (-3065 3610);
PAINT MONO (-3065 3610);
DISPLAY INVISIBLE (-3065 3610);
FORCEPROP 1 LASTPIN (-3075 3600) BN 13
J 0
(-3087 3608);
DISPLAY 0.489362 (-3087 3608);
PAINT MONO (-3087 3608);
FORCEPROP 2 LAST CDS_LIB mstr_standard
J 0
(-3025 3600);
DISPLAY INVISIBLE (-3025 3600);
FORCEPROP 1 LAST BODY_TYPE PLUMBING
J 0
(-3025 3650);
DISPLAY 0.872340 (-3025 3650);
PAINT GREEN (-3025 3650);
DISPLAY INVISIBLE (-3025 3650);
FORCEPROP 1 LAST HDL_TAP TRUE
J 0
(-2700 3475);
DISPLAY 0.872340 (-2700 3475);
DISPLAY INVISIBLE (-2700 3475);
FORCEPROP 1 LAST PATH I726
J 0
(-3027 3600);
DISPLAY 0.872340 (-3027 3600);
PAINT GREEN (-3027 3600);
DISPLAY INVISIBLE (-3027 3600);
FORCEADD TAP..1
(-3025 3700);
FORCEPROP 3 LASTPIN (-3075 3700) SIG_NAME M_A_CPU0_SB_DQ<11>
J 0
(-3065 3710);
DISPLAY 0.659574 (-3065 3710);
PAINT MONO (-3065 3710);
DISPLAY INVISIBLE (-3065 3710);
FORCEPROP 1 LASTPIN (-3075 3700) BN 11
J 0
(-3087 3708);
DISPLAY 0.489362 (-3087 3708);
PAINT MONO (-3087 3708);
FORCEPROP 2 LAST CDS_LIB mstr_standard
J 0
(-3025 3700);
DISPLAY INVISIBLE (-3025 3700);
FORCEPROP 1 LAST BODY_TYPE PLUMBING
J 0
(-3025 3750);
DISPLAY 0.872340 (-3025 3750);
PAINT GREEN (-3025 3750);
DISPLAY INVISIBLE (-3025 3750);
FORCEPROP 1 LAST HDL_TAP TRUE
J 0
(-2700 3575);
DISPLAY 0.872340 (-2700 3575);
DISPLAY INVISIBLE (-2700 3575);
FORCEPROP 1 LAST PATH I727
J 0
(-3027 3700);
DISPLAY 0.872340 (-3027 3700);
PAINT GREEN (-3027 3700);
DISPLAY INVISIBLE (-3027 3700);
FORCEADD TAP..1
(-3025 3650);
FORCEPROP 3 LASTPIN (-3075 3650) SIG_NAME M_A_CPU0_SB_DQ<12>
J 0
(-3065 3660);
DISPLAY 0.659574 (-3065 3660);
PAINT MONO (-3065 3660);
DISPLAY INVISIBLE (-3065 3660);
FORCEPROP 1 LASTPIN (-3075 3650) BN 12
J 0
(-3087 3658);
DISPLAY 0.489362 (-3087 3658);
PAINT MONO (-3087 3658);
FORCEPROP 2 LAST CDS_LIB mstr_standard
J 0
(-3025 3650);
DISPLAY INVISIBLE (-3025 3650);
FORCEPROP 1 LAST BODY_TYPE PLUMBING
J 0
(-3025 3700);
DISPLAY 0.872340 (-3025 3700);
PAINT GREEN (-3025 3700);
DISPLAY INVISIBLE (-3025 3700);
FORCEPROP 1 LAST HDL_TAP TRUE
J 0
(-2700 3525);
DISPLAY 0.872340 (-2700 3525);
DISPLAY INVISIBLE (-2700 3525);
FORCEPROP 1 LAST PATH I728
J 0
(-3027 3650);
DISPLAY 0.872340 (-3027 3650);
PAINT GREEN (-3027 3650);
DISPLAY INVISIBLE (-3027 3650);
FORCEADD TAP..1
(-3025 3750);
FORCEPROP 3 LASTPIN (-3075 3750) SIG_NAME M_A_CPU0_SB_DQ<10>
J 0
(-3065 3760);
DISPLAY 0.659574 (-3065 3760);
PAINT MONO (-3065 3760);
DISPLAY INVISIBLE (-3065 3760);
FORCEPROP 1 LASTPIN (-3075 3750) BN 10
J 0
(-3087 3758);
DISPLAY 0.489362 (-3087 3758);
PAINT MONO (-3087 3758);
FORCEPROP 2 LAST CDS_LIB mstr_standard
J 0
(-3025 3750);
DISPLAY INVISIBLE (-3025 3750);
FORCEPROP 1 LAST BODY_TYPE PLUMBING
J 0
(-3025 3800);
DISPLAY 0.872340 (-3025 3800);
PAINT GREEN (-3025 3800);
DISPLAY INVISIBLE (-3025 3800);
FORCEPROP 1 LAST HDL_TAP TRUE
J 0
(-2700 3625);
DISPLAY 0.872340 (-2700 3625);
DISPLAY INVISIBLE (-2700 3625);
FORCEPROP 1 LAST PATH I729
J 0
(-3027 3750);
DISPLAY 0.872340 (-3027 3750);
PAINT GREEN (-3027 3750);
DISPLAY INVISIBLE (-3027 3750);
FORCEADD TAP..1
(-3025 3550);
FORCEPROP 3 LASTPIN (-3075 3550) SIG_NAME M_A_CPU0_SB_DQ<14>
J 0
(-3065 3560);
DISPLAY 0.659574 (-3065 3560);
PAINT MONO (-3065 3560);
DISPLAY INVISIBLE (-3065 3560);
FORCEPROP 1 LASTPIN (-3075 3550) BN 14
J 0
(-3087 3558);
DISPLAY 0.489362 (-3087 3558);
PAINT MONO (-3087 3558);
FORCEPROP 2 LAST CDS_LIB mstr_standard
J 0
(-3025 3550);
DISPLAY INVISIBLE (-3025 3550);
FORCEPROP 1 LAST BODY_TYPE PLUMBING
J 0
(-3025 3600);
DISPLAY 0.872340 (-3025 3600);
PAINT GREEN (-3025 3600);
DISPLAY INVISIBLE (-3025 3600);
FORCEPROP 1 LAST HDL_TAP TRUE
J 0
(-2700 3425);
DISPLAY 0.872340 (-2700 3425);
DISPLAY INVISIBLE (-2700 3425);
FORCEPROP 1 LAST PATH I730
J 0
(-3027 3550);
DISPLAY 0.872340 (-3027 3550);
PAINT GREEN (-3027 3550);
DISPLAY INVISIBLE (-3027 3550);
FORCEADD TAP..1
(-3025 3400);
FORCEPROP 3 LASTPIN (-3075 3400) SIG_NAME M_A_CPU0_SB_DQ<16>
J 0
(-3065 3410);
DISPLAY 0.659574 (-3065 3410);
PAINT MONO (-3065 3410);
DISPLAY INVISIBLE (-3065 3410);
FORCEPROP 1 LASTPIN (-3075 3400) BN 16
J 0
(-3087 3408);
DISPLAY 0.489362 (-3087 3408);
PAINT MONO (-3087 3408);
FORCEPROP 2 LAST CDS_LIB mstr_standard
J 0
(-3025 3400);
DISPLAY INVISIBLE (-3025 3400);
FORCEPROP 1 LAST BODY_TYPE PLUMBING
J 0
(-3025 3450);
DISPLAY 0.872340 (-3025 3450);
PAINT GREEN (-3025 3450);
DISPLAY INVISIBLE (-3025 3450);
FORCEPROP 1 LAST HDL_TAP TRUE
J 0
(-2700 3275);
DISPLAY 0.872340 (-2700 3275);
DISPLAY INVISIBLE (-2700 3275);
FORCEPROP 1 LAST PATH I731
J 0
(-3027 3400);
DISPLAY 0.872340 (-3027 3400);
PAINT GREEN (-3027 3400);
DISPLAY INVISIBLE (-3027 3400);
FORCEADD TAP..1
(-3025 3350);
FORCEPROP 3 LASTPIN (-3075 3350) SIG_NAME M_A_CPU0_SB_DQ<17>
J 0
(-3065 3360);
DISPLAY 0.659574 (-3065 3360);
PAINT MONO (-3065 3360);
DISPLAY INVISIBLE (-3065 3360);
FORCEPROP 1 LASTPIN (-3075 3350) BN 17
J 0
(-3087 3358);
DISPLAY 0.489362 (-3087 3358);
PAINT MONO (-3087 3358);
FORCEPROP 2 LAST CDS_LIB mstr_standard
J 0
(-3025 3350);
DISPLAY INVISIBLE (-3025 3350);
FORCEPROP 1 LAST BODY_TYPE PLUMBING
J 0
(-3025 3400);
DISPLAY 0.872340 (-3025 3400);
PAINT GREEN (-3025 3400);
DISPLAY INVISIBLE (-3025 3400);
FORCEPROP 1 LAST HDL_TAP TRUE
J 0
(-2700 3225);
DISPLAY 0.872340 (-2700 3225);
DISPLAY INVISIBLE (-2700 3225);
FORCEPROP 1 LAST PATH I732
J 0
(-3027 3350);
DISPLAY 0.872340 (-3027 3350);
PAINT GREEN (-3027 3350);
DISPLAY INVISIBLE (-3027 3350);
FORCEADD TAP..1
(-3025 3500);
FORCEPROP 3 LASTPIN (-3075 3500) SIG_NAME M_A_CPU0_SB_DQ<15>
J 0
(-3065 3510);
DISPLAY 0.659574 (-3065 3510);
PAINT MONO (-3065 3510);
DISPLAY INVISIBLE (-3065 3510);
FORCEPROP 1 LASTPIN (-3075 3500) BN 15
J 0
(-3087 3508);
DISPLAY 0.489362 (-3087 3508);
PAINT MONO (-3087 3508);
FORCEPROP 2 LAST CDS_LIB mstr_standard
J 0
(-3025 3500);
DISPLAY INVISIBLE (-3025 3500);
FORCEPROP 1 LAST BODY_TYPE PLUMBING
J 0
(-3025 3550);
DISPLAY 0.872340 (-3025 3550);
PAINT GREEN (-3025 3550);
DISPLAY INVISIBLE (-3025 3550);
FORCEPROP 1 LAST HDL_TAP TRUE
J 0
(-2700 3375);
DISPLAY 0.872340 (-2700 3375);
DISPLAY INVISIBLE (-2700 3375);
FORCEPROP 1 LAST PATH I733
J 0
(-3027 3500);
DISPLAY 0.872340 (-3027 3500);
PAINT GREEN (-3027 3500);
DISPLAY INVISIBLE (-3027 3500);
FORCEADD TAP..1
(-3025 3300);
FORCEPROP 3 LASTPIN (-3075 3300) SIG_NAME M_A_CPU0_SB_DQ<18>
J 0
(-3065 3310);
DISPLAY 0.659574 (-3065 3310);
PAINT MONO (-3065 3310);
DISPLAY INVISIBLE (-3065 3310);
FORCEPROP 1 LASTPIN (-3075 3300) BN 18
J 0
(-3087 3308);
DISPLAY 0.489362 (-3087 3308);
PAINT MONO (-3087 3308);
FORCEPROP 2 LAST CDS_LIB mstr_standard
J 0
(-3025 3300);
DISPLAY INVISIBLE (-3025 3300);
FORCEPROP 1 LAST BODY_TYPE PLUMBING
J 0
(-3025 3350);
DISPLAY 0.872340 (-3025 3350);
PAINT GREEN (-3025 3350);
DISPLAY INVISIBLE (-3025 3350);
FORCEPROP 1 LAST HDL_TAP TRUE
J 0
(-2700 3175);
DISPLAY 0.872340 (-2700 3175);
DISPLAY INVISIBLE (-2700 3175);
FORCEPROP 1 LAST PATH I734
J 0
(-3027 3300);
DISPLAY 0.872340 (-3027 3300);
PAINT GREEN (-3027 3300);
DISPLAY INVISIBLE (-3027 3300);
FORCEADD TAP..1
(-3025 3100);
FORCEPROP 3 LASTPIN (-3075 3100) SIG_NAME M_A_CPU0_SB_DQ<22>
J 0
(-3065 3110);
DISPLAY 0.659574 (-3065 3110);
PAINT MONO (-3065 3110);
DISPLAY INVISIBLE (-3065 3110);
FORCEPROP 1 LASTPIN (-3075 3100) BN 22
J 0
(-3087 3108);
DISPLAY 0.489362 (-3087 3108);
PAINT MONO (-3087 3108);
FORCEPROP 2 LAST CDS_LIB mstr_standard
J 0
(-3025 3100);
DISPLAY INVISIBLE (-3025 3100);
FORCEPROP 1 LAST BODY_TYPE PLUMBING
J 0
(-3025 3150);
DISPLAY 0.872340 (-3025 3150);
PAINT GREEN (-3025 3150);
DISPLAY INVISIBLE (-3025 3150);
FORCEPROP 1 LAST HDL_TAP TRUE
J 0
(-2700 2975);
DISPLAY 0.872340 (-2700 2975);
DISPLAY INVISIBLE (-2700 2975);
FORCEPROP 1 LAST PATH I735
J 0
(-3027 3100);
DISPLAY 0.872340 (-3027 3100);
PAINT GREEN (-3027 3100);
DISPLAY INVISIBLE (-3027 3100);
FORCEADD TAP..1
(-3025 3150);
FORCEPROP 3 LASTPIN (-3075 3150) SIG_NAME M_A_CPU0_SB_DQ<21>
J 0
(-3065 3160);
DISPLAY 0.659574 (-3065 3160);
PAINT MONO (-3065 3160);
DISPLAY INVISIBLE (-3065 3160);
FORCEPROP 1 LASTPIN (-3075 3150) BN 21
J 0
(-3087 3158);
DISPLAY 0.489362 (-3087 3158);
PAINT MONO (-3087 3158);
FORCEPROP 2 LAST CDS_LIB mstr_standard
J 0
(-3025 3150);
DISPLAY INVISIBLE (-3025 3150);
FORCEPROP 1 LAST BODY_TYPE PLUMBING
J 0
(-3025 3200);
DISPLAY 0.872340 (-3025 3200);
PAINT GREEN (-3025 3200);
DISPLAY INVISIBLE (-3025 3200);
FORCEPROP 1 LAST HDL_TAP TRUE
J 0
(-2700 3025);
DISPLAY 0.872340 (-2700 3025);
DISPLAY INVISIBLE (-2700 3025);
FORCEPROP 1 LAST PATH I736
J 0
(-3027 3150);
DISPLAY 0.872340 (-3027 3150);
PAINT GREEN (-3027 3150);
DISPLAY INVISIBLE (-3027 3150);
FORCEADD TAP..1
(-3025 3200);
FORCEPROP 3 LASTPIN (-3075 3200) SIG_NAME M_A_CPU0_SB_DQ<20>
J 0
(-3065 3210);
DISPLAY 0.659574 (-3065 3210);
PAINT MONO (-3065 3210);
DISPLAY INVISIBLE (-3065 3210);
FORCEPROP 1 LASTPIN (-3075 3200) BN 20
J 0
(-3087 3208);
DISPLAY 0.489362 (-3087 3208);
PAINT MONO (-3087 3208);
FORCEPROP 2 LAST CDS_LIB mstr_standard
J 0
(-3025 3200);
DISPLAY INVISIBLE (-3025 3200);
FORCEPROP 1 LAST BODY_TYPE PLUMBING
J 0
(-3025 3250);
DISPLAY 0.872340 (-3025 3250);
PAINT GREEN (-3025 3250);
DISPLAY INVISIBLE (-3025 3250);
FORCEPROP 1 LAST HDL_TAP TRUE
J 0
(-2700 3075);
DISPLAY 0.872340 (-2700 3075);
DISPLAY INVISIBLE (-2700 3075);
FORCEPROP 1 LAST PATH I737
J 0
(-3027 3200);
DISPLAY 0.872340 (-3027 3200);
PAINT GREEN (-3027 3200);
DISPLAY INVISIBLE (-3027 3200);
FORCEADD TAP..1
(-3025 3250);
FORCEPROP 3 LASTPIN (-3075 3250) SIG_NAME M_A_CPU0_SB_DQ<19>
J 0
(-3065 3260);
DISPLAY 0.659574 (-3065 3260);
PAINT MONO (-3065 3260);
DISPLAY INVISIBLE (-3065 3260);
FORCEPROP 1 LASTPIN (-3075 3250) BN 19
J 0
(-3087 3258);
DISPLAY 0.489362 (-3087 3258);
PAINT MONO (-3087 3258);
FORCEPROP 2 LAST CDS_LIB mstr_standard
J 0
(-3025 3250);
DISPLAY INVISIBLE (-3025 3250);
FORCEPROP 1 LAST BODY_TYPE PLUMBING
J 0
(-3025 3300);
DISPLAY 0.872340 (-3025 3300);
PAINT GREEN (-3025 3300);
DISPLAY INVISIBLE (-3025 3300);
FORCEPROP 1 LAST HDL_TAP TRUE
J 0
(-2700 3125);
DISPLAY 0.872340 (-2700 3125);
DISPLAY INVISIBLE (-2700 3125);
FORCEPROP 1 LAST PATH I738
J 0
(-3027 3250);
DISPLAY 0.872340 (-3027 3250);
PAINT GREEN (-3027 3250);
DISPLAY INVISIBLE (-3027 3250);
FORCEADD TAP..1
(-3025 3050);
FORCEPROP 3 LASTPIN (-3075 3050) SIG_NAME M_A_CPU0_SB_DQ<23>
J 0
(-3065 3060);
DISPLAY 0.659574 (-3065 3060);
PAINT MONO (-3065 3060);
DISPLAY INVISIBLE (-3065 3060);
FORCEPROP 1 LASTPIN (-3075 3050) BN 23
J 0
(-3087 3058);
DISPLAY 0.489362 (-3087 3058);
PAINT MONO (-3087 3058);
FORCEPROP 2 LAST CDS_LIB mstr_standard
J 0
(-3025 3050);
DISPLAY INVISIBLE (-3025 3050);
FORCEPROP 1 LAST BODY_TYPE PLUMBING
J 0
(-3025 3100);
DISPLAY 0.872340 (-3025 3100);
PAINT GREEN (-3025 3100);
DISPLAY INVISIBLE (-3025 3100);
FORCEPROP 1 LAST HDL_TAP TRUE
J 0
(-2700 2925);
DISPLAY 0.872340 (-2700 2925);
DISPLAY INVISIBLE (-2700 2925);
FORCEPROP 1 LAST PATH I739
J 0
(-3027 3050);
DISPLAY 0.872340 (-3027 3050);
PAINT GREEN (-3027 3050);
DISPLAY INVISIBLE (-3027 3050);
FORCEADD OFFPAGE..6
R 2
(-2425 2550);
FORCEPROP 2 LAST $XR0 86 
J 0
(-2211 2550);
DISPLAY 0.638298 (-2211 2550);
PAINT MONO (-2211 2550);
FORCEPROP 2 LAST CDS_LIB mstr_standard
J 0
(-2425 2550);
DISPLAY INVISIBLE (-2425 2550);
FORCEPROP 1 LAST OFFPAGE TRUE
J 2
(-2750 2425);
DISPLAY 0.872340 (-2750 2425);
PAINT GREEN (-2750 2425);
DISPLAY INVISIBLE (-2750 2425);
FORCEPROP 1 LAST COMMENT_BODY TRUE
J 2
(-2525 2475);
DISPLAY 0.872340 (-2525 2475);
PAINT GREEN (-2525 2475);
DISPLAY INVISIBLE (-2525 2475);
FORCEPROP 2 LAST PATH I740
J 0
(-2200 2600);
DISPLAY 1.021277 (-2200 2600);
DISPLAY INVISIBLE (-2200 2600);
FORCEADD OFFPAGE..6
R 2
(-2425 2100);
FORCEPROP 2 LAST $XR0 86 
J 0
(-2211 2100);
DISPLAY 0.638298 (-2211 2100);
PAINT MONO (-2211 2100);
FORCEPROP 2 LAST CDS_LIB mstr_standard
J 0
(-2425 2100);
DISPLAY INVISIBLE (-2425 2100);
FORCEPROP 1 LAST OFFPAGE TRUE
J 2
(-2750 1975);
DISPLAY 0.872340 (-2750 1975);
PAINT GREEN (-2750 1975);
DISPLAY INVISIBLE (-2750 1975);
FORCEPROP 1 LAST COMMENT_BODY TRUE
J 2
(-2525 2025);
DISPLAY 0.872340 (-2525 2025);
PAINT GREEN (-2525 2025);
DISPLAY INVISIBLE (-2525 2025);
FORCEPROP 2 LAST PATH I741
J 0
(-2200 2150);
DISPLAY 1.021277 (-2200 2150);
DISPLAY INVISIBLE (-2200 2150);
FORCEADD TAP..1
(-3025 2900);
FORCEPROP 3 LASTPIN (-3075 2900) SIG_NAME M_A_CPU0_SB_DQ<25>
J 0
(-3065 2910);
DISPLAY 0.659574 (-3065 2910);
PAINT MONO (-3065 2910);
DISPLAY INVISIBLE (-3065 2910);
FORCEPROP 1 LASTPIN (-3075 2900) BN 25
J 0
(-3087 2908);
DISPLAY 0.489362 (-3087 2908);
PAINT MONO (-3087 2908);
FORCEPROP 2 LAST CDS_LIB mstr_standard
J 0
(-3025 2900);
DISPLAY INVISIBLE (-3025 2900);
FORCEPROP 1 LAST BODY_TYPE PLUMBING
J 0
(-3025 2950);
DISPLAY 0.872340 (-3025 2950);
PAINT GREEN (-3025 2950);
DISPLAY INVISIBLE (-3025 2950);
FORCEPROP 1 LAST HDL_TAP TRUE
J 0
(-2700 2775);
DISPLAY 0.872340 (-2700 2775);
DISPLAY INVISIBLE (-2700 2775);
FORCEPROP 1 LAST PATH I742
J 0
(-3027 2900);
DISPLAY 0.872340 (-3027 2900);
PAINT GREEN (-3027 2900);
DISPLAY INVISIBLE (-3027 2900);
FORCEADD TAP..1
(-3025 2850);
FORCEPROP 3 LASTPIN (-3075 2850) SIG_NAME M_A_CPU0_SB_DQ<26>
J 0
(-3065 2860);
DISPLAY 0.659574 (-3065 2860);
PAINT MONO (-3065 2860);
DISPLAY INVISIBLE (-3065 2860);
FORCEPROP 1 LASTPIN (-3075 2850) BN 26
J 0
(-3087 2858);
DISPLAY 0.489362 (-3087 2858);
PAINT MONO (-3087 2858);
FORCEPROP 2 LAST CDS_LIB mstr_standard
J 0
(-3025 2850);
DISPLAY INVISIBLE (-3025 2850);
FORCEPROP 1 LAST BODY_TYPE PLUMBING
J 0
(-3025 2900);
DISPLAY 0.872340 (-3025 2900);
PAINT GREEN (-3025 2900);
DISPLAY INVISIBLE (-3025 2900);
FORCEPROP 1 LAST HDL_TAP TRUE
J 0
(-2700 2725);
DISPLAY 0.872340 (-2700 2725);
DISPLAY INVISIBLE (-2700 2725);
FORCEPROP 1 LAST PATH I743
J 0
(-3027 2850);
DISPLAY 0.872340 (-3027 2850);
PAINT GREEN (-3027 2850);
DISPLAY INVISIBLE (-3027 2850);
FORCEADD TAP..1
(-3025 2950);
FORCEPROP 3 LASTPIN (-3075 2950) SIG_NAME M_A_CPU0_SB_DQ<24>
J 0
(-3065 2960);
DISPLAY 0.659574 (-3065 2960);
PAINT MONO (-3065 2960);
DISPLAY INVISIBLE (-3065 2960);
FORCEPROP 1 LASTPIN (-3075 2950) BN 24
J 0
(-3087 2958);
DISPLAY 0.489362 (-3087 2958);
PAINT MONO (-3087 2958);
FORCEPROP 2 LAST CDS_LIB mstr_standard
J 0
(-3025 2950);
DISPLAY INVISIBLE (-3025 2950);
FORCEPROP 1 LAST BODY_TYPE PLUMBING
J 0
(-3025 3000);
DISPLAY 0.872340 (-3025 3000);
PAINT GREEN (-3025 3000);
DISPLAY INVISIBLE (-3025 3000);
FORCEPROP 1 LAST HDL_TAP TRUE
J 0
(-2700 2825);
DISPLAY 0.872340 (-2700 2825);
DISPLAY INVISIBLE (-2700 2825);
FORCEPROP 1 LAST PATH I744
J 0
(-3027 2950);
DISPLAY 0.872340 (-3027 2950);
PAINT GREEN (-3027 2950);
DISPLAY INVISIBLE (-3027 2950);
FORCEADD TAP..1
(-3025 2750);
FORCEPROP 3 LASTPIN (-3075 2750) SIG_NAME M_A_CPU0_SB_DQ<28>
J 0
(-3065 2760);
DISPLAY 0.659574 (-3065 2760);
PAINT MONO (-3065 2760);
DISPLAY INVISIBLE (-3065 2760);
FORCEPROP 1 LASTPIN (-3075 2750) BN 28
J 0
(-3087 2758);
DISPLAY 0.489362 (-3087 2758);
PAINT MONO (-3087 2758);
FORCEPROP 2 LAST CDS_LIB mstr_standard
J 0
(-3025 2750);
DISPLAY INVISIBLE (-3025 2750);
FORCEPROP 1 LAST BODY_TYPE PLUMBING
J 0
(-3025 2800);
DISPLAY 0.872340 (-3025 2800);
PAINT GREEN (-3025 2800);
DISPLAY INVISIBLE (-3025 2800);
FORCEPROP 1 LAST HDL_TAP TRUE
J 0
(-2700 2625);
DISPLAY 0.872340 (-2700 2625);
DISPLAY INVISIBLE (-2700 2625);
FORCEPROP 1 LAST PATH I745
J 0
(-3027 2750);
DISPLAY 0.872340 (-3027 2750);
PAINT GREEN (-3027 2750);
DISPLAY INVISIBLE (-3027 2750);
FORCEADD TAP..1
(-3025 2800);
FORCEPROP 3 LASTPIN (-3075 2800) SIG_NAME M_A_CPU0_SB_DQ<27>
J 0
(-3065 2810);
DISPLAY 0.659574 (-3065 2810);
PAINT MONO (-3065 2810);
DISPLAY INVISIBLE (-3065 2810);
FORCEPROP 1 LASTPIN (-3075 2800) BN 27
J 0
(-3087 2808);
DISPLAY 0.489362 (-3087 2808);
PAINT MONO (-3087 2808);
FORCEPROP 2 LAST CDS_LIB mstr_standard
J 0
(-3025 2800);
DISPLAY INVISIBLE (-3025 2800);
FORCEPROP 1 LAST BODY_TYPE PLUMBING
J 0
(-3025 2850);
DISPLAY 0.872340 (-3025 2850);
PAINT GREEN (-3025 2850);
DISPLAY INVISIBLE (-3025 2850);
FORCEPROP 1 LAST HDL_TAP TRUE
J 0
(-2700 2675);
DISPLAY 0.872340 (-2700 2675);
DISPLAY INVISIBLE (-2700 2675);
FORCEPROP 1 LAST PATH I746
J 0
(-3027 2800);
DISPLAY 0.872340 (-3027 2800);
PAINT GREEN (-3027 2800);
DISPLAY INVISIBLE (-3027 2800);
FORCEADD TAP..1
(-3025 2600);
FORCEPROP 3 LASTPIN (-3075 2600) SIG_NAME M_A_CPU0_SB_DQ<31>
J 0
(-3065 2610);
DISPLAY 0.659574 (-3065 2610);
PAINT MONO (-3065 2610);
DISPLAY INVISIBLE (-3065 2610);
FORCEPROP 1 LASTPIN (-3075 2600) BN 31
J 0
(-3087 2608);
DISPLAY 0.489362 (-3087 2608);
PAINT MONO (-3087 2608);
FORCEPROP 2 LAST CDS_LIB mstr_standard
J 0
(-3025 2600);
DISPLAY INVISIBLE (-3025 2600);
FORCEPROP 1 LAST BODY_TYPE PLUMBING
J 0
(-3025 2650);
DISPLAY 0.872340 (-3025 2650);
PAINT GREEN (-3025 2650);
DISPLAY INVISIBLE (-3025 2650);
FORCEPROP 1 LAST HDL_TAP TRUE
J 0
(-2700 2475);
DISPLAY 0.872340 (-2700 2475);
DISPLAY INVISIBLE (-2700 2475);
FORCEPROP 1 LAST PATH I747
J 0
(-3027 2600);
DISPLAY 0.872340 (-3027 2600);
PAINT GREEN (-3027 2600);
DISPLAY INVISIBLE (-3027 2600);
FORCEADD TAP..1
(-3025 2650);
FORCEPROP 3 LASTPIN (-3075 2650) SIG_NAME M_A_CPU0_SB_DQ<30>
J 0
(-3065 2660);
DISPLAY 0.659574 (-3065 2660);
PAINT MONO (-3065 2660);
DISPLAY INVISIBLE (-3065 2660);
FORCEPROP 1 LASTPIN (-3075 2650) BN 30
J 0
(-3087 2658);
DISPLAY 0.489362 (-3087 2658);
PAINT MONO (-3087 2658);
FORCEPROP 2 LAST CDS_LIB mstr_standard
J 0
(-3025 2650);
DISPLAY INVISIBLE (-3025 2650);
FORCEPROP 1 LAST BODY_TYPE PLUMBING
J 0
(-3025 2700);
DISPLAY 0.872340 (-3025 2700);
PAINT GREEN (-3025 2700);
DISPLAY INVISIBLE (-3025 2700);
FORCEPROP 1 LAST HDL_TAP TRUE
J 0
(-2700 2525);
DISPLAY 0.872340 (-2700 2525);
DISPLAY INVISIBLE (-2700 2525);
FORCEPROP 1 LAST PATH I748
J 0
(-3027 2650);
DISPLAY 0.872340 (-3027 2650);
PAINT GREEN (-3027 2650);
DISPLAY INVISIBLE (-3027 2650);
FORCEADD TAP..1
(-3025 2700);
FORCEPROP 3 LASTPIN (-3075 2700) SIG_NAME M_A_CPU0_SB_DQ<29>
J 0
(-3065 2710);
DISPLAY 0.659574 (-3065 2710);
PAINT MONO (-3065 2710);
DISPLAY INVISIBLE (-3065 2710);
FORCEPROP 1 LASTPIN (-3075 2700) BN 29
J 0
(-3087 2708);
DISPLAY 0.489362 (-3087 2708);
PAINT MONO (-3087 2708);
FORCEPROP 2 LAST CDS_LIB mstr_standard
J 0
(-3025 2700);
DISPLAY INVISIBLE (-3025 2700);
FORCEPROP 1 LAST BODY_TYPE PLUMBING
J 0
(-3025 2750);
DISPLAY 0.872340 (-3025 2750);
PAINT GREEN (-3025 2750);
DISPLAY INVISIBLE (-3025 2750);
FORCEPROP 1 LAST HDL_TAP TRUE
J 0
(-2700 2575);
DISPLAY 0.872340 (-2700 2575);
DISPLAY INVISIBLE (-2700 2575);
FORCEPROP 1 LAST PATH I749
J 0
(-3027 2700);
DISPLAY 0.872340 (-3027 2700);
PAINT GREEN (-3027 2700);
DISPLAY INVISIBLE (-3027 2700);
FORCEADD TAP..1
(-3025 2500);
FORCEPROP 3 LASTPIN (-3075 2500) SIG_NAME M_A_CPU0_SA_CB<0>
J 0
(-3065 2510);
DISPLAY 0.659574 (-3065 2510);
PAINT MONO (-3065 2510);
DISPLAY INVISIBLE (-3065 2510);
FORCEPROP 1 LASTPIN (-3075 2500) BN 0
J 0
(-3087 2508);
DISPLAY 0.489362 (-3087 2508);
PAINT MONO (-3087 2508);
FORCEPROP 2 LAST CDS_LIB mstr_standard
J 0
(-3025 2500);
DISPLAY INVISIBLE (-3025 2500);
FORCEPROP 1 LAST BODY_TYPE PLUMBING
J 0
(-3025 2550);
DISPLAY 0.872340 (-3025 2550);
PAINT GREEN (-3025 2550);
DISPLAY INVISIBLE (-3025 2550);
FORCEPROP 1 LAST HDL_TAP TRUE
J 0
(-2700 2375);
DISPLAY 0.872340 (-2700 2375);
DISPLAY INVISIBLE (-2700 2375);
FORCEPROP 1 LAST PATH I750
J 0
(-3027 2500);
DISPLAY 0.872340 (-3027 2500);
PAINT GREEN (-3027 2500);
DISPLAY INVISIBLE (-3027 2500);
FORCEADD TAP..1
(-3025 2400);
FORCEPROP 3 LASTPIN (-3075 2400) SIG_NAME M_A_CPU0_SA_CB<2>
J 0
(-3065 2410);
DISPLAY 0.659574 (-3065 2410);
PAINT MONO (-3065 2410);
DISPLAY INVISIBLE (-3065 2410);
FORCEPROP 1 LASTPIN (-3075 2400) BN 2
J 0
(-3087 2408);
DISPLAY 0.489362 (-3087 2408);
PAINT MONO (-3087 2408);
FORCEPROP 2 LAST CDS_LIB mstr_standard
J 0
(-3025 2400);
DISPLAY INVISIBLE (-3025 2400);
FORCEPROP 1 LAST BODY_TYPE PLUMBING
J 0
(-3025 2450);
DISPLAY 0.872340 (-3025 2450);
PAINT GREEN (-3025 2450);
DISPLAY INVISIBLE (-3025 2450);
FORCEPROP 1 LAST HDL_TAP TRUE
J 0
(-2700 2275);
DISPLAY 0.872340 (-2700 2275);
DISPLAY INVISIBLE (-2700 2275);
FORCEPROP 1 LAST PATH I751
J 0
(-3027 2400);
DISPLAY 0.872340 (-3027 2400);
PAINT GREEN (-3027 2400);
DISPLAY INVISIBLE (-3027 2400);
FORCEADD TAP..1
(-3025 2450);
FORCEPROP 3 LASTPIN (-3075 2450) SIG_NAME M_A_CPU0_SA_CB<1>
J 0
(-3065 2460);
DISPLAY 0.659574 (-3065 2460);
PAINT MONO (-3065 2460);
DISPLAY INVISIBLE (-3065 2460);
FORCEPROP 1 LASTPIN (-3075 2450) BN 1
J 0
(-3087 2458);
DISPLAY 0.489362 (-3087 2458);
PAINT MONO (-3087 2458);
FORCEPROP 2 LAST CDS_LIB mstr_standard
J 0
(-3025 2450);
DISPLAY INVISIBLE (-3025 2450);
FORCEPROP 1 LAST BODY_TYPE PLUMBING
J 0
(-3025 2500);
DISPLAY 0.872340 (-3025 2500);
PAINT GREEN (-3025 2500);
DISPLAY INVISIBLE (-3025 2500);
FORCEPROP 1 LAST HDL_TAP TRUE
J 0
(-2700 2325);
DISPLAY 0.872340 (-2700 2325);
DISPLAY INVISIBLE (-2700 2325);
FORCEPROP 1 LAST PATH I752
J 0
(-3027 2450);
DISPLAY 0.872340 (-3027 2450);
PAINT GREEN (-3027 2450);
DISPLAY INVISIBLE (-3027 2450);
FORCEADD TAP..1
(-3025 2350);
FORCEPROP 3 LASTPIN (-3075 2350) SIG_NAME M_A_CPU0_SA_CB<3>
J 0
(-3065 2360);
DISPLAY 0.659574 (-3065 2360);
PAINT MONO (-3065 2360);
DISPLAY INVISIBLE (-3065 2360);
FORCEPROP 1 LASTPIN (-3075 2350) BN 3
J 0
(-3087 2358);
DISPLAY 0.489362 (-3087 2358);
PAINT MONO (-3087 2358);
FORCEPROP 2 LAST CDS_LIB mstr_standard
J 0
(-3025 2350);
DISPLAY INVISIBLE (-3025 2350);
FORCEPROP 1 LAST BODY_TYPE PLUMBING
J 0
(-3025 2400);
DISPLAY 0.872340 (-3025 2400);
PAINT GREEN (-3025 2400);
DISPLAY INVISIBLE (-3025 2400);
FORCEPROP 1 LAST HDL_TAP TRUE
J 0
(-2700 2225);
DISPLAY 0.872340 (-2700 2225);
DISPLAY INVISIBLE (-2700 2225);
FORCEPROP 1 LAST PATH I753
J 0
(-3027 2350);
DISPLAY 0.872340 (-3027 2350);
PAINT GREEN (-3027 2350);
DISPLAY INVISIBLE (-3027 2350);
FORCEADD TAP..1
(-3025 2300);
FORCEPROP 3 LASTPIN (-3075 2300) SIG_NAME M_A_CPU0_SA_CB<4>
J 0
(-3065 2310);
DISPLAY 0.659574 (-3065 2310);
PAINT MONO (-3065 2310);
DISPLAY INVISIBLE (-3065 2310);
FORCEPROP 1 LASTPIN (-3075 2300) BN 4
J 0
(-3087 2308);
DISPLAY 0.489362 (-3087 2308);
PAINT MONO (-3087 2308);
FORCEPROP 2 LAST CDS_LIB mstr_standard
J 0
(-3025 2300);
DISPLAY INVISIBLE (-3025 2300);
FORCEPROP 1 LAST BODY_TYPE PLUMBING
J 0
(-3025 2350);
DISPLAY 0.872340 (-3025 2350);
PAINT GREEN (-3025 2350);
DISPLAY INVISIBLE (-3025 2350);
FORCEPROP 1 LAST HDL_TAP TRUE
J 0
(-2700 2175);
DISPLAY 0.872340 (-2700 2175);
DISPLAY INVISIBLE (-2700 2175);
FORCEPROP 1 LAST PATH I754
J 0
(-3027 2300);
DISPLAY 0.872340 (-3027 2300);
PAINT GREEN (-3027 2300);
DISPLAY INVISIBLE (-3027 2300);
FORCEADD TAP..1
(-3025 2250);
FORCEPROP 3 LASTPIN (-3075 2250) SIG_NAME M_A_CPU0_SA_CB<5>
J 0
(-3065 2260);
DISPLAY 0.659574 (-3065 2260);
PAINT MONO (-3065 2260);
DISPLAY INVISIBLE (-3065 2260);
FORCEPROP 1 LASTPIN (-3075 2250) BN 5
J 0
(-3087 2258);
DISPLAY 0.489362 (-3087 2258);
PAINT MONO (-3087 2258);
FORCEPROP 2 LAST CDS_LIB mstr_standard
J 0
(-3025 2250);
DISPLAY INVISIBLE (-3025 2250);
FORCEPROP 1 LAST BODY_TYPE PLUMBING
J 0
(-3025 2300);
DISPLAY 0.872340 (-3025 2300);
PAINT GREEN (-3025 2300);
DISPLAY INVISIBLE (-3025 2300);
FORCEPROP 1 LAST HDL_TAP TRUE
J 0
(-2700 2125);
DISPLAY 0.872340 (-2700 2125);
DISPLAY INVISIBLE (-2700 2125);
FORCEPROP 1 LAST PATH I755
J 0
(-3027 2250);
DISPLAY 0.872340 (-3027 2250);
PAINT GREEN (-3027 2250);
DISPLAY INVISIBLE (-3027 2250);
FORCEADD TAP..1
(-3025 2050);
FORCEPROP 3 LASTPIN (-3075 2050) SIG_NAME M_A_CPU0_SB_CB<0>
J 0
(-3065 2060);
DISPLAY 0.659574 (-3065 2060);
PAINT MONO (-3065 2060);
DISPLAY INVISIBLE (-3065 2060);
FORCEPROP 1 LASTPIN (-3075 2050) BN 0
J 0
(-3087 2058);
DISPLAY 0.489362 (-3087 2058);
PAINT MONO (-3087 2058);
FORCEPROP 2 LAST CDS_LIB mstr_standard
J 0
(-3025 2050);
DISPLAY INVISIBLE (-3025 2050);
FORCEPROP 1 LAST BODY_TYPE PLUMBING
J 0
(-3025 2100);
DISPLAY 0.872340 (-3025 2100);
PAINT GREEN (-3025 2100);
DISPLAY INVISIBLE (-3025 2100);
FORCEPROP 1 LAST HDL_TAP TRUE
J 0
(-2700 1925);
DISPLAY 0.872340 (-2700 1925);
DISPLAY INVISIBLE (-2700 1925);
FORCEPROP 1 LAST PATH I756
J 0
(-3027 2050);
DISPLAY 0.872340 (-3027 2050);
PAINT GREEN (-3027 2050);
DISPLAY INVISIBLE (-3027 2050);
FORCEADD TAP..1
(-3025 2150);
FORCEPROP 3 LASTPIN (-3075 2150) SIG_NAME M_A_CPU0_SA_CB<7>
J 0
(-3065 2160);
DISPLAY 0.659574 (-3065 2160);
PAINT MONO (-3065 2160);
DISPLAY INVISIBLE (-3065 2160);
FORCEPROP 1 LASTPIN (-3075 2150) BN 7
J 0
(-3087 2158);
DISPLAY 0.489362 (-3087 2158);
PAINT MONO (-3087 2158);
FORCEPROP 2 LAST CDS_LIB mstr_standard
J 0
(-3025 2150);
DISPLAY INVISIBLE (-3025 2150);
FORCEPROP 1 LAST BODY_TYPE PLUMBING
J 0
(-3025 2200);
DISPLAY 0.872340 (-3025 2200);
PAINT GREEN (-3025 2200);
DISPLAY INVISIBLE (-3025 2200);
FORCEPROP 1 LAST HDL_TAP TRUE
J 0
(-2700 2025);
DISPLAY 0.872340 (-2700 2025);
DISPLAY INVISIBLE (-2700 2025);
FORCEPROP 1 LAST PATH I757
J 0
(-3027 2150);
DISPLAY 0.872340 (-3027 2150);
PAINT GREEN (-3027 2150);
DISPLAY INVISIBLE (-3027 2150);
FORCEADD TAP..1
(-3025 2200);
FORCEPROP 3 LASTPIN (-3075 2200) SIG_NAME M_A_CPU0_SA_CB<6>
J 0
(-3065 2210);
DISPLAY 0.659574 (-3065 2210);
PAINT MONO (-3065 2210);
DISPLAY INVISIBLE (-3065 2210);
FORCEPROP 1 LASTPIN (-3075 2200) BN 6
J 0
(-3087 2208);
DISPLAY 0.489362 (-3087 2208);
PAINT MONO (-3087 2208);
FORCEPROP 2 LAST CDS_LIB mstr_standard
J 0
(-3025 2200);
DISPLAY INVISIBLE (-3025 2200);
FORCEPROP 1 LAST BODY_TYPE PLUMBING
J 0
(-3025 2250);
DISPLAY 0.872340 (-3025 2250);
PAINT GREEN (-3025 2250);
DISPLAY INVISIBLE (-3025 2250);
FORCEPROP 1 LAST HDL_TAP TRUE
J 0
(-2700 2075);
DISPLAY 0.872340 (-2700 2075);
DISPLAY INVISIBLE (-2700 2075);
FORCEPROP 1 LAST PATH I758
J 0
(-3027 2200);
DISPLAY 0.872340 (-3027 2200);
PAINT GREEN (-3027 2200);
DISPLAY INVISIBLE (-3027 2200);
FORCEADD TAP..1
(-3025 2000);
FORCEPROP 3 LASTPIN (-3075 2000) SIG_NAME M_A_CPU0_SB_CB<1>
J 0
(-3065 2010);
DISPLAY 0.659574 (-3065 2010);
PAINT MONO (-3065 2010);
DISPLAY INVISIBLE (-3065 2010);
FORCEPROP 1 LASTPIN (-3075 2000) BN 1
J 0
(-3087 2008);
DISPLAY 0.489362 (-3087 2008);
PAINT MONO (-3087 2008);
FORCEPROP 2 LAST CDS_LIB mstr_standard
J 0
(-3025 2000);
DISPLAY INVISIBLE (-3025 2000);
FORCEPROP 1 LAST BODY_TYPE PLUMBING
J 0
(-3025 2050);
DISPLAY 0.872340 (-3025 2050);
PAINT GREEN (-3025 2050);
DISPLAY INVISIBLE (-3025 2050);
FORCEPROP 1 LAST HDL_TAP TRUE
J 0
(-2700 1875);
DISPLAY 0.872340 (-2700 1875);
DISPLAY INVISIBLE (-2700 1875);
FORCEPROP 1 LAST PATH I759
J 0
(-3027 2000);
DISPLAY 0.872340 (-3027 2000);
PAINT GREEN (-3027 2000);
DISPLAY INVISIBLE (-3027 2000);
FORCEADD TAP..1
(-3025 1950);
FORCEPROP 3 LASTPIN (-3075 1950) SIG_NAME M_A_CPU0_SB_CB<2>
J 0
(-3065 1960);
DISPLAY 0.659574 (-3065 1960);
PAINT MONO (-3065 1960);
DISPLAY INVISIBLE (-3065 1960);
FORCEPROP 1 LASTPIN (-3075 1950) BN 2
J 0
(-3087 1958);
DISPLAY 0.489362 (-3087 1958);
PAINT MONO (-3087 1958);
FORCEPROP 2 LAST CDS_LIB mstr_standard
J 0
(-3025 1950);
DISPLAY INVISIBLE (-3025 1950);
FORCEPROP 1 LAST BODY_TYPE PLUMBING
J 0
(-3025 2000);
DISPLAY 0.872340 (-3025 2000);
PAINT GREEN (-3025 2000);
DISPLAY INVISIBLE (-3025 2000);
FORCEPROP 1 LAST HDL_TAP TRUE
J 0
(-2700 1825);
DISPLAY 0.872340 (-2700 1825);
DISPLAY INVISIBLE (-2700 1825);
FORCEPROP 1 LAST PATH I760
J 0
(-3027 1950);
DISPLAY 0.872340 (-3027 1950);
PAINT GREEN (-3027 1950);
DISPLAY INVISIBLE (-3027 1950);
FORCEADD TAP..1
(-3025 1900);
FORCEPROP 3 LASTPIN (-3075 1900) SIG_NAME M_A_CPU0_SB_CB<3>
J 0
(-3065 1910);
DISPLAY 0.659574 (-3065 1910);
PAINT MONO (-3065 1910);
DISPLAY INVISIBLE (-3065 1910);
FORCEPROP 1 LASTPIN (-3075 1900) BN 3
J 0
(-3087 1908);
DISPLAY 0.489362 (-3087 1908);
PAINT MONO (-3087 1908);
FORCEPROP 2 LAST CDS_LIB mstr_standard
J 0
(-3025 1900);
DISPLAY INVISIBLE (-3025 1900);
FORCEPROP 1 LAST BODY_TYPE PLUMBING
J 0
(-3025 1950);
DISPLAY 0.872340 (-3025 1950);
PAINT GREEN (-3025 1950);
DISPLAY INVISIBLE (-3025 1950);
FORCEPROP 1 LAST HDL_TAP TRUE
J 0
(-2700 1775);
DISPLAY 0.872340 (-2700 1775);
DISPLAY INVISIBLE (-2700 1775);
FORCEPROP 1 LAST PATH I761
J 0
(-3027 1900);
DISPLAY 0.872340 (-3027 1900);
PAINT GREEN (-3027 1900);
DISPLAY INVISIBLE (-3027 1900);
FORCEADD TAP..1
(-3025 1850);
FORCEPROP 3 LASTPIN (-3075 1850) SIG_NAME M_A_CPU0_SB_CB<4>
J 0
(-3065 1860);
DISPLAY 0.659574 (-3065 1860);
PAINT MONO (-3065 1860);
DISPLAY INVISIBLE (-3065 1860);
FORCEPROP 1 LASTPIN (-3075 1850) BN 4
J 0
(-3087 1858);
DISPLAY 0.489362 (-3087 1858);
PAINT MONO (-3087 1858);
FORCEPROP 2 LAST CDS_LIB mstr_standard
J 0
(-3025 1850);
DISPLAY INVISIBLE (-3025 1850);
FORCEPROP 1 LAST BODY_TYPE PLUMBING
J 0
(-3025 1900);
DISPLAY 0.872340 (-3025 1900);
PAINT GREEN (-3025 1900);
DISPLAY INVISIBLE (-3025 1900);
FORCEPROP 1 LAST HDL_TAP TRUE
J 0
(-2700 1725);
DISPLAY 0.872340 (-2700 1725);
DISPLAY INVISIBLE (-2700 1725);
FORCEPROP 1 LAST PATH I762
J 0
(-3027 1850);
DISPLAY 0.872340 (-3027 1850);
PAINT GREEN (-3027 1850);
DISPLAY INVISIBLE (-3027 1850);
FORCEADD TAP..1
(-3025 1800);
FORCEPROP 3 LASTPIN (-3075 1800) SIG_NAME M_A_CPU0_SB_CB<5>
J 0
(-3065 1810);
DISPLAY 0.659574 (-3065 1810);
PAINT MONO (-3065 1810);
DISPLAY INVISIBLE (-3065 1810);
FORCEPROP 1 LASTPIN (-3075 1800) BN 5
J 0
(-3087 1808);
DISPLAY 0.489362 (-3087 1808);
PAINT MONO (-3087 1808);
FORCEPROP 2 LAST CDS_LIB mstr_standard
J 0
(-3025 1800);
DISPLAY INVISIBLE (-3025 1800);
FORCEPROP 1 LAST BODY_TYPE PLUMBING
J 0
(-3025 1850);
DISPLAY 0.872340 (-3025 1850);
PAINT GREEN (-3025 1850);
DISPLAY INVISIBLE (-3025 1850);
FORCEPROP 1 LAST HDL_TAP TRUE
J 0
(-2700 1675);
DISPLAY 0.872340 (-2700 1675);
DISPLAY INVISIBLE (-2700 1675);
FORCEPROP 1 LAST PATH I763
J 0
(-3027 1800);
DISPLAY 0.872340 (-3027 1800);
PAINT GREEN (-3027 1800);
DISPLAY INVISIBLE (-3027 1800);
FORCEADD TAP..1
(-3025 1750);
FORCEPROP 3 LASTPIN (-3075 1750) SIG_NAME M_A_CPU0_SB_CB<6>
J 0
(-3065 1760);
DISPLAY 0.659574 (-3065 1760);
PAINT MONO (-3065 1760);
DISPLAY INVISIBLE (-3065 1760);
FORCEPROP 1 LASTPIN (-3075 1750) BN 6
J 0
(-3087 1758);
DISPLAY 0.489362 (-3087 1758);
PAINT MONO (-3087 1758);
FORCEPROP 2 LAST CDS_LIB mstr_standard
J 0
(-3025 1750);
DISPLAY INVISIBLE (-3025 1750);
FORCEPROP 1 LAST BODY_TYPE PLUMBING
J 0
(-3025 1800);
DISPLAY 0.872340 (-3025 1800);
PAINT GREEN (-3025 1800);
DISPLAY INVISIBLE (-3025 1800);
FORCEPROP 1 LAST HDL_TAP TRUE
J 0
(-2700 1625);
DISPLAY 0.872340 (-2700 1625);
DISPLAY INVISIBLE (-2700 1625);
FORCEPROP 1 LAST PATH I764
J 0
(-3027 1750);
DISPLAY 0.872340 (-3027 1750);
PAINT GREEN (-3027 1750);
DISPLAY INVISIBLE (-3027 1750);
FORCEADD TAP..1
(-3025 1700);
FORCEPROP 3 LASTPIN (-3075 1700) SIG_NAME M_A_CPU0_SB_CB<7>
J 0
(-3065 1710);
DISPLAY 0.659574 (-3065 1710);
PAINT MONO (-3065 1710);
DISPLAY INVISIBLE (-3065 1710);
FORCEPROP 1 LASTPIN (-3075 1700) BN 7
J 0
(-3087 1708);
DISPLAY 0.489362 (-3087 1708);
PAINT MONO (-3087 1708);
FORCEPROP 2 LAST CDS_LIB mstr_standard
J 0
(-3025 1700);
DISPLAY INVISIBLE (-3025 1700);
FORCEPROP 1 LAST BODY_TYPE PLUMBING
J 0
(-3025 1750);
DISPLAY 0.872340 (-3025 1750);
PAINT GREEN (-3025 1750);
DISPLAY INVISIBLE (-3025 1750);
FORCEPROP 1 LAST HDL_TAP TRUE
J 0
(-2700 1575);
DISPLAY 0.872340 (-2700 1575);
DISPLAY INVISIBLE (-2700 1575);
FORCEPROP 1 LAST PATH I765
J 0
(-3027 1700);
DISPLAY 0.872340 (-3027 1700);
PAINT GREEN (-3027 1700);
DISPLAY INVISIBLE (-3027 1700);
FORCEADD TAP..1
R 2
(-5550 6100);
FORCEPROP 3 LASTPIN (-5500 6100) SIG_NAME M_A_CPU0_SA_DQS_DP<0>
J 0
(-5490 6110);
DISPLAY 0.659574 (-5490 6110);
PAINT MONO (-5490 6110);
DISPLAY INVISIBLE (-5490 6110);
FORCEPROP 1 LASTPIN (-5500 6100) BN 0
J 2
(-5488 6108);
DISPLAY 0.489362 (-5488 6108);
PAINT MONO (-5488 6108);
FORCEPROP 2 LAST CDS_LIB mstr_standard
J 0
(-5550 6100);
DISPLAY INVISIBLE (-5550 6100);
FORCEPROP 1 LAST BODY_TYPE PLUMBING
J 2
(-5550 6150);
DISPLAY 0.872340 (-5550 6150);
PAINT GREEN (-5550 6150);
DISPLAY INVISIBLE (-5550 6150);
FORCEPROP 1 LAST HDL_TAP TRUE
J 2
(-5875 5975);
DISPLAY 0.872340 (-5875 5975);
DISPLAY INVISIBLE (-5875 5975);
FORCEPROP 1 LAST PATH I766
J 2
(-5548 6100);
DISPLAY 0.872340 (-5548 6100);
PAINT GREEN (-5548 6100);
DISPLAY INVISIBLE (-5548 6100);
FORCEADD TAP..1
R 2
(-5550 6000);
FORCEPROP 3 LASTPIN (-5500 6000) SIG_NAME M_A_CPU0_SA_DQS_DP<1>
J 0
(-5490 6010);
DISPLAY 0.659574 (-5490 6010);
PAINT MONO (-5490 6010);
DISPLAY INVISIBLE (-5490 6010);
FORCEPROP 1 LASTPIN (-5500 6000) BN 1
J 2
(-5488 6008);
DISPLAY 0.489362 (-5488 6008);
PAINT MONO (-5488 6008);
FORCEPROP 2 LAST CDS_LIB mstr_standard
J 0
(-5550 6000);
DISPLAY INVISIBLE (-5550 6000);
FORCEPROP 1 LAST BODY_TYPE PLUMBING
J 2
(-5550 6050);
DISPLAY 0.872340 (-5550 6050);
PAINT GREEN (-5550 6050);
DISPLAY INVISIBLE (-5550 6050);
FORCEPROP 1 LAST HDL_TAP TRUE
J 2
(-5875 5875);
DISPLAY 0.872340 (-5875 5875);
DISPLAY INVISIBLE (-5875 5875);
FORCEPROP 1 LAST PATH I767
J 2
(-5548 6000);
DISPLAY 0.872340 (-5548 6000);
PAINT GREEN (-5548 6000);
DISPLAY INVISIBLE (-5548 6000);
FORCEADD TAP..1
R 2
(-5550 5900);
FORCEPROP 3 LASTPIN (-5500 5900) SIG_NAME M_A_CPU0_SA_DQS_DP<2>
J 0
(-5490 5910);
DISPLAY 0.659574 (-5490 5910);
PAINT MONO (-5490 5910);
DISPLAY INVISIBLE (-5490 5910);
FORCEPROP 1 LASTPIN (-5500 5900) BN 2
J 2
(-5488 5908);
DISPLAY 0.489362 (-5488 5908);
PAINT MONO (-5488 5908);
FORCEPROP 2 LAST CDS_LIB mstr_standard
J 0
(-5550 5900);
DISPLAY INVISIBLE (-5550 5900);
FORCEPROP 1 LAST BODY_TYPE PLUMBING
J 2
(-5550 5950);
DISPLAY 0.872340 (-5550 5950);
PAINT GREEN (-5550 5950);
DISPLAY INVISIBLE (-5550 5950);
FORCEPROP 1 LAST HDL_TAP TRUE
J 2
(-5875 5775);
DISPLAY 0.872340 (-5875 5775);
DISPLAY INVISIBLE (-5875 5775);
FORCEPROP 1 LAST PATH I768
J 2
(-5548 5900);
DISPLAY 0.872340 (-5548 5900);
PAINT GREEN (-5548 5900);
DISPLAY INVISIBLE (-5548 5900);
FORCEADD TAP..1
R 2
(-5550 5800);
FORCEPROP 3 LASTPIN (-5500 5800) SIG_NAME M_A_CPU0_SA_DQS_DP<3>
J 0
(-5490 5810);
DISPLAY 0.659574 (-5490 5810);
PAINT MONO (-5490 5810);
DISPLAY INVISIBLE (-5490 5810);
FORCEPROP 1 LASTPIN (-5500 5800) BN 3
J 2
(-5488 5808);
DISPLAY 0.489362 (-5488 5808);
PAINT MONO (-5488 5808);
FORCEPROP 2 LAST CDS_LIB mstr_standard
J 0
(-5550 5800);
DISPLAY INVISIBLE (-5550 5800);
FORCEPROP 1 LAST BODY_TYPE PLUMBING
J 2
(-5550 5850);
DISPLAY 0.872340 (-5550 5850);
PAINT GREEN (-5550 5850);
DISPLAY INVISIBLE (-5550 5850);
FORCEPROP 1 LAST HDL_TAP TRUE
J 2
(-5875 5675);
DISPLAY 0.872340 (-5875 5675);
DISPLAY INVISIBLE (-5875 5675);
FORCEPROP 1 LAST PATH I769
J 2
(-5548 5800);
DISPLAY 0.872340 (-5548 5800);
PAINT GREEN (-5548 5800);
DISPLAY INVISIBLE (-5548 5800);
FORCEADD TAP..1
R 2
(-5550 5700);
FORCEPROP 3 LASTPIN (-5500 5700) SIG_NAME M_A_CPU0_SA_DQS_DP<4>
J 0
(-5490 5710);
DISPLAY 0.659574 (-5490 5710);
PAINT MONO (-5490 5710);
DISPLAY INVISIBLE (-5490 5710);
FORCEPROP 1 LASTPIN (-5500 5700) BN 4
J 2
(-5488 5708);
DISPLAY 0.489362 (-5488 5708);
PAINT MONO (-5488 5708);
FORCEPROP 2 LAST CDS_LIB mstr_standard
J 0
(-5550 5700);
DISPLAY INVISIBLE (-5550 5700);
FORCEPROP 1 LAST BODY_TYPE PLUMBING
J 2
(-5550 5750);
DISPLAY 0.872340 (-5550 5750);
PAINT GREEN (-5550 5750);
DISPLAY INVISIBLE (-5550 5750);
FORCEPROP 1 LAST HDL_TAP TRUE
J 2
(-5875 5575);
DISPLAY 0.872340 (-5875 5575);
DISPLAY INVISIBLE (-5875 5575);
FORCEPROP 1 LAST PATH I770
J 2
(-5548 5700);
DISPLAY 0.872340 (-5548 5700);
PAINT GREEN (-5548 5700);
DISPLAY INVISIBLE (-5548 5700);
FORCEADD TAP..1
R 2
(-5550 5600);
FORCEPROP 3 LASTPIN (-5500 5600) SIG_NAME M_A_CPU0_SA_DQS_DP<5>
J 0
(-5490 5610);
DISPLAY 0.659574 (-5490 5610);
PAINT MONO (-5490 5610);
DISPLAY INVISIBLE (-5490 5610);
FORCEPROP 1 LASTPIN (-5500 5600) BN 5
J 2
(-5488 5608);
DISPLAY 0.489362 (-5488 5608);
PAINT MONO (-5488 5608);
FORCEPROP 2 LAST CDS_LIB mstr_standard
J 0
(-5550 5600);
DISPLAY INVISIBLE (-5550 5600);
FORCEPROP 1 LAST BODY_TYPE PLUMBING
J 2
(-5550 5650);
DISPLAY 0.872340 (-5550 5650);
PAINT GREEN (-5550 5650);
DISPLAY INVISIBLE (-5550 5650);
FORCEPROP 1 LAST HDL_TAP TRUE
J 2
(-5875 5475);
DISPLAY 0.872340 (-5875 5475);
DISPLAY INVISIBLE (-5875 5475);
FORCEPROP 1 LAST PATH I771
J 2
(-5548 5600);
DISPLAY 0.872340 (-5548 5600);
PAINT GREEN (-5548 5600);
DISPLAY INVISIBLE (-5548 5600);
FORCEADD TAP..1
R 2
(-5550 5500);
FORCEPROP 3 LASTPIN (-5500 5500) SIG_NAME M_A_CPU0_SA_DQS_DP<6>
J 0
(-5490 5510);
DISPLAY 0.659574 (-5490 5510);
PAINT MONO (-5490 5510);
DISPLAY INVISIBLE (-5490 5510);
FORCEPROP 1 LASTPIN (-5500 5500) BN 6
J 2
(-5488 5508);
DISPLAY 0.489362 (-5488 5508);
PAINT MONO (-5488 5508);
FORCEPROP 2 LAST CDS_LIB mstr_standard
J 0
(-5550 5500);
DISPLAY INVISIBLE (-5550 5500);
FORCEPROP 1 LAST BODY_TYPE PLUMBING
J 2
(-5550 5550);
DISPLAY 0.872340 (-5550 5550);
PAINT GREEN (-5550 5550);
DISPLAY INVISIBLE (-5550 5550);
FORCEPROP 1 LAST HDL_TAP TRUE
J 2
(-5875 5375);
DISPLAY 0.872340 (-5875 5375);
DISPLAY INVISIBLE (-5875 5375);
FORCEPROP 1 LAST PATH I772
J 2
(-5548 5500);
DISPLAY 0.872340 (-5548 5500);
PAINT GREEN (-5548 5500);
DISPLAY INVISIBLE (-5548 5500);
FORCEADD TAP..1
R 2
(-5550 5400);
FORCEPROP 3 LASTPIN (-5500 5400) SIG_NAME M_A_CPU0_SA_DQS_DP<7>
J 0
(-5490 5410);
DISPLAY 0.659574 (-5490 5410);
PAINT MONO (-5490 5410);
DISPLAY INVISIBLE (-5490 5410);
FORCEPROP 1 LASTPIN (-5500 5400) BN 7
J 2
(-5488 5408);
DISPLAY 0.489362 (-5488 5408);
PAINT MONO (-5488 5408);
FORCEPROP 2 LAST CDS_LIB mstr_standard
J 0
(-5550 5400);
DISPLAY INVISIBLE (-5550 5400);
FORCEPROP 1 LAST BODY_TYPE PLUMBING
J 2
(-5550 5450);
DISPLAY 0.872340 (-5550 5450);
PAINT GREEN (-5550 5450);
DISPLAY INVISIBLE (-5550 5450);
FORCEPROP 1 LAST HDL_TAP TRUE
J 2
(-5875 5275);
DISPLAY 0.872340 (-5875 5275);
DISPLAY INVISIBLE (-5875 5275);
FORCEPROP 1 LAST PATH I773
J 2
(-5548 5400);
DISPLAY 0.872340 (-5548 5400);
PAINT GREEN (-5548 5400);
DISPLAY INVISIBLE (-5548 5400);
FORCEADD TAP..1
R 2
(-5550 5300);
FORCEPROP 3 LASTPIN (-5500 5300) SIG_NAME M_A_CPU0_SA_DQS_DP<8>
J 0
(-5490 5310);
DISPLAY 0.659574 (-5490 5310);
PAINT MONO (-5490 5310);
DISPLAY INVISIBLE (-5490 5310);
FORCEPROP 1 LASTPIN (-5500 5300) BN 8
J 2
(-5488 5308);
DISPLAY 0.489362 (-5488 5308);
PAINT MONO (-5488 5308);
FORCEPROP 2 LAST CDS_LIB mstr_standard
J 0
(-5550 5300);
DISPLAY INVISIBLE (-5550 5300);
FORCEPROP 1 LAST BODY_TYPE PLUMBING
J 2
(-5550 5350);
DISPLAY 0.872340 (-5550 5350);
PAINT GREEN (-5550 5350);
DISPLAY INVISIBLE (-5550 5350);
FORCEPROP 1 LAST HDL_TAP TRUE
J 2
(-5875 5175);
DISPLAY 0.872340 (-5875 5175);
DISPLAY INVISIBLE (-5875 5175);
FORCEPROP 1 LAST PATH I774
J 2
(-5548 5300);
DISPLAY 0.872340 (-5548 5300);
PAINT GREEN (-5548 5300);
DISPLAY INVISIBLE (-5548 5300);
FORCEADD TAP..1
R 2
(-5550 5200);
FORCEPROP 3 LASTPIN (-5500 5200) SIG_NAME M_A_CPU0_SA_DQS_DP<9>
J 0
(-5490 5210);
DISPLAY 0.659574 (-5490 5210);
PAINT MONO (-5490 5210);
DISPLAY INVISIBLE (-5490 5210);
FORCEPROP 1 LASTPIN (-5500 5200) BN 9
J 2
(-5488 5208);
DISPLAY 0.489362 (-5488 5208);
PAINT MONO (-5488 5208);
FORCEPROP 2 LAST CDS_LIB mstr_standard
J 0
(-5550 5200);
DISPLAY INVISIBLE (-5550 5200);
FORCEPROP 1 LAST BODY_TYPE PLUMBING
J 2
(-5550 5250);
DISPLAY 0.872340 (-5550 5250);
PAINT GREEN (-5550 5250);
DISPLAY INVISIBLE (-5550 5250);
FORCEPROP 1 LAST HDL_TAP TRUE
J 2
(-5875 5075);
DISPLAY 0.872340 (-5875 5075);
DISPLAY INVISIBLE (-5875 5075);
FORCEPROP 1 LAST PATH I775
J 2
(-5548 5200);
DISPLAY 0.872340 (-5548 5200);
PAINT GREEN (-5548 5200);
DISPLAY INVISIBLE (-5548 5200);
FORCEADD TAP..1
R 2
(-5750 5950);
FORCEPROP 3 LASTPIN (-5700 5950) SIG_NAME M_A_CPU0_SA_DQS_DN<1>
J 0
(-5690 5960);
DISPLAY 0.659574 (-5690 5960);
PAINT MONO (-5690 5960);
DISPLAY INVISIBLE (-5690 5960);
FORCEPROP 1 LASTPIN (-5700 5950) BN 1
J 2
(-5688 5958);
DISPLAY 0.489362 (-5688 5958);
PAINT MONO (-5688 5958);
FORCEPROP 2 LAST CDS_LIB mstr_standard
J 0
(-5750 5950);
DISPLAY INVISIBLE (-5750 5950);
FORCEPROP 1 LAST BODY_TYPE PLUMBING
J 2
(-5750 6000);
DISPLAY 0.872340 (-5750 6000);
PAINT GREEN (-5750 6000);
DISPLAY INVISIBLE (-5750 6000);
FORCEPROP 1 LAST HDL_TAP TRUE
J 2
(-6075 5825);
DISPLAY 0.872340 (-6075 5825);
DISPLAY INVISIBLE (-6075 5825);
FORCEPROP 1 LAST PATH I776
J 2
(-5748 5950);
DISPLAY 0.872340 (-5748 5950);
PAINT GREEN (-5748 5950);
DISPLAY INVISIBLE (-5748 5950);
FORCEADD TAP..1
R 2
(-5750 6050);
FORCEPROP 3 LASTPIN (-5700 6050) SIG_NAME M_A_CPU0_SA_DQS_DN<0>
J 0
(-5690 6060);
DISPLAY 0.659574 (-5690 6060);
PAINT MONO (-5690 6060);
DISPLAY INVISIBLE (-5690 6060);
FORCEPROP 1 LASTPIN (-5700 6050) BN 0
J 2
(-5688 6058);
DISPLAY 0.489362 (-5688 6058);
PAINT MONO (-5688 6058);
FORCEPROP 2 LAST CDS_LIB mstr_standard
J 0
(-5750 6050);
DISPLAY INVISIBLE (-5750 6050);
FORCEPROP 1 LAST BODY_TYPE PLUMBING
J 2
(-5750 6100);
DISPLAY 0.872340 (-5750 6100);
PAINT GREEN (-5750 6100);
DISPLAY INVISIBLE (-5750 6100);
FORCEPROP 1 LAST HDL_TAP TRUE
J 2
(-6075 5925);
DISPLAY 0.872340 (-6075 5925);
DISPLAY INVISIBLE (-6075 5925);
FORCEPROP 1 LAST PATH I777
J 2
(-5748 6050);
DISPLAY 0.872340 (-5748 6050);
PAINT GREEN (-5748 6050);
DISPLAY INVISIBLE (-5748 6050);
FORCEADD TAP..1
R 2
(-5750 5650);
FORCEPROP 3 LASTPIN (-5700 5650) SIG_NAME M_A_CPU0_SA_DQS_DN<4>
J 0
(-5690 5660);
DISPLAY 0.659574 (-5690 5660);
PAINT MONO (-5690 5660);
DISPLAY INVISIBLE (-5690 5660);
FORCEPROP 1 LASTPIN (-5700 5650) BN 4
J 2
(-5688 5658);
DISPLAY 0.489362 (-5688 5658);
PAINT MONO (-5688 5658);
FORCEPROP 2 LAST CDS_LIB mstr_standard
J 0
(-5750 5650);
DISPLAY INVISIBLE (-5750 5650);
FORCEPROP 1 LAST BODY_TYPE PLUMBING
J 2
(-5750 5700);
DISPLAY 0.872340 (-5750 5700);
PAINT GREEN (-5750 5700);
DISPLAY INVISIBLE (-5750 5700);
FORCEPROP 1 LAST HDL_TAP TRUE
J 2
(-6075 5525);
DISPLAY 0.872340 (-6075 5525);
DISPLAY INVISIBLE (-6075 5525);
FORCEPROP 1 LAST PATH I778
J 2
(-5748 5650);
DISPLAY 0.872340 (-5748 5650);
PAINT GREEN (-5748 5650);
DISPLAY INVISIBLE (-5748 5650);
FORCEADD TAP..1
R 2
(-5750 5750);
FORCEPROP 3 LASTPIN (-5700 5750) SIG_NAME M_A_CPU0_SA_DQS_DN<3>
J 0
(-5690 5760);
DISPLAY 0.659574 (-5690 5760);
PAINT MONO (-5690 5760);
DISPLAY INVISIBLE (-5690 5760);
FORCEPROP 1 LASTPIN (-5700 5750) BN 3
J 2
(-5688 5758);
DISPLAY 0.489362 (-5688 5758);
PAINT MONO (-5688 5758);
FORCEPROP 2 LAST CDS_LIB mstr_standard
J 0
(-5750 5750);
DISPLAY INVISIBLE (-5750 5750);
FORCEPROP 1 LAST BODY_TYPE PLUMBING
J 2
(-5750 5800);
DISPLAY 0.872340 (-5750 5800);
PAINT GREEN (-5750 5800);
DISPLAY INVISIBLE (-5750 5800);
FORCEPROP 1 LAST HDL_TAP TRUE
J 2
(-6075 5625);
DISPLAY 0.872340 (-6075 5625);
DISPLAY INVISIBLE (-6075 5625);
FORCEPROP 1 LAST PATH I779
J 2
(-5748 5750);
DISPLAY 0.872340 (-5748 5750);
PAINT GREEN (-5748 5750);
DISPLAY INVISIBLE (-5748 5750);
FORCEADD TAP..1
R 2
(-5750 5850);
FORCEPROP 3 LASTPIN (-5700 5850) SIG_NAME M_A_CPU0_SA_DQS_DN<2>
J 0
(-5690 5860);
DISPLAY 0.659574 (-5690 5860);
PAINT MONO (-5690 5860);
DISPLAY INVISIBLE (-5690 5860);
FORCEPROP 1 LASTPIN (-5700 5850) BN 2
J 2
(-5688 5858);
DISPLAY 0.489362 (-5688 5858);
PAINT MONO (-5688 5858);
FORCEPROP 2 LAST CDS_LIB mstr_standard
J 0
(-5750 5850);
DISPLAY INVISIBLE (-5750 5850);
FORCEPROP 1 LAST BODY_TYPE PLUMBING
J 2
(-5750 5900);
DISPLAY 0.872340 (-5750 5900);
PAINT GREEN (-5750 5900);
DISPLAY INVISIBLE (-5750 5900);
FORCEPROP 1 LAST HDL_TAP TRUE
J 2
(-6075 5725);
DISPLAY 0.872340 (-6075 5725);
DISPLAY INVISIBLE (-6075 5725);
FORCEPROP 1 LAST PATH I780
J 2
(-5748 5850);
DISPLAY 0.872340 (-5748 5850);
PAINT GREEN (-5748 5850);
DISPLAY INVISIBLE (-5748 5850);
FORCEADD TAP..1
R 2
(-5750 5450);
FORCEPROP 3 LASTPIN (-5700 5450) SIG_NAME M_A_CPU0_SA_DQS_DN<6>
J 0
(-5690 5460);
DISPLAY 0.659574 (-5690 5460);
PAINT MONO (-5690 5460);
DISPLAY INVISIBLE (-5690 5460);
FORCEPROP 1 LASTPIN (-5700 5450) BN 6
J 2
(-5688 5458);
DISPLAY 0.489362 (-5688 5458);
PAINT MONO (-5688 5458);
FORCEPROP 2 LAST CDS_LIB mstr_standard
J 0
(-5750 5450);
DISPLAY INVISIBLE (-5750 5450);
FORCEPROP 1 LAST BODY_TYPE PLUMBING
J 2
(-5750 5500);
DISPLAY 0.872340 (-5750 5500);
PAINT GREEN (-5750 5500);
DISPLAY INVISIBLE (-5750 5500);
FORCEPROP 1 LAST HDL_TAP TRUE
J 2
(-6075 5325);
DISPLAY 0.872340 (-6075 5325);
DISPLAY INVISIBLE (-6075 5325);
FORCEPROP 1 LAST PATH I781
J 2
(-5748 5450);
DISPLAY 0.872340 (-5748 5450);
PAINT GREEN (-5748 5450);
DISPLAY INVISIBLE (-5748 5450);
FORCEADD TAP..1
R 2
(-5750 5550);
FORCEPROP 3 LASTPIN (-5700 5550) SIG_NAME M_A_CPU0_SA_DQS_DN<5>
J 0
(-5690 5560);
DISPLAY 0.659574 (-5690 5560);
PAINT MONO (-5690 5560);
DISPLAY INVISIBLE (-5690 5560);
FORCEPROP 1 LASTPIN (-5700 5550) BN 5
J 2
(-5688 5558);
DISPLAY 0.489362 (-5688 5558);
PAINT MONO (-5688 5558);
FORCEPROP 2 LAST CDS_LIB mstr_standard
J 0
(-5750 5550);
DISPLAY INVISIBLE (-5750 5550);
FORCEPROP 1 LAST BODY_TYPE PLUMBING
J 2
(-5750 5600);
DISPLAY 0.872340 (-5750 5600);
PAINT GREEN (-5750 5600);
DISPLAY INVISIBLE (-5750 5600);
FORCEPROP 1 LAST HDL_TAP TRUE
J 2
(-6075 5425);
DISPLAY 0.872340 (-6075 5425);
DISPLAY INVISIBLE (-6075 5425);
FORCEPROP 1 LAST PATH I782
J 2
(-5748 5550);
DISPLAY 0.872340 (-5748 5550);
PAINT GREEN (-5748 5550);
DISPLAY INVISIBLE (-5748 5550);
FORCEADD TAP..1
R 2
(-5750 5150);
FORCEPROP 3 LASTPIN (-5700 5150) SIG_NAME M_A_CPU0_SA_DQS_DN<9>
J 0
(-5690 5160);
DISPLAY 0.659574 (-5690 5160);
PAINT MONO (-5690 5160);
DISPLAY INVISIBLE (-5690 5160);
FORCEPROP 1 LASTPIN (-5700 5150) BN 9
J 2
(-5688 5158);
DISPLAY 0.489362 (-5688 5158);
PAINT MONO (-5688 5158);
FORCEPROP 2 LAST CDS_LIB mstr_standard
J 0
(-5750 5150);
DISPLAY INVISIBLE (-5750 5150);
FORCEPROP 1 LAST BODY_TYPE PLUMBING
J 2
(-5750 5200);
DISPLAY 0.872340 (-5750 5200);
PAINT GREEN (-5750 5200);
DISPLAY INVISIBLE (-5750 5200);
FORCEPROP 1 LAST HDL_TAP TRUE
J 2
(-6075 5025);
DISPLAY 0.872340 (-6075 5025);
DISPLAY INVISIBLE (-6075 5025);
FORCEPROP 1 LAST PATH I783
J 2
(-5748 5150);
DISPLAY 0.872340 (-5748 5150);
PAINT GREEN (-5748 5150);
DISPLAY INVISIBLE (-5748 5150);
FORCEADD TAP..1
R 2
(-5750 5250);
FORCEPROP 3 LASTPIN (-5700 5250) SIG_NAME M_A_CPU0_SA_DQS_DN<8>
J 0
(-5690 5260);
DISPLAY 0.659574 (-5690 5260);
PAINT MONO (-5690 5260);
DISPLAY INVISIBLE (-5690 5260);
FORCEPROP 1 LASTPIN (-5700 5250) BN 8
J 2
(-5688 5258);
DISPLAY 0.489362 (-5688 5258);
PAINT MONO (-5688 5258);
FORCEPROP 2 LAST CDS_LIB mstr_standard
J 0
(-5750 5250);
DISPLAY INVISIBLE (-5750 5250);
FORCEPROP 1 LAST BODY_TYPE PLUMBING
J 2
(-5750 5300);
DISPLAY 0.872340 (-5750 5300);
PAINT GREEN (-5750 5300);
DISPLAY INVISIBLE (-5750 5300);
FORCEPROP 1 LAST HDL_TAP TRUE
J 2
(-6075 5125);
DISPLAY 0.872340 (-6075 5125);
DISPLAY INVISIBLE (-6075 5125);
FORCEPROP 1 LAST PATH I784
J 2
(-5748 5250);
DISPLAY 0.872340 (-5748 5250);
PAINT GREEN (-5748 5250);
DISPLAY INVISIBLE (-5748 5250);
FORCEADD TAP..1
R 2
(-5750 5350);
FORCEPROP 3 LASTPIN (-5700 5350) SIG_NAME M_A_CPU0_SA_DQS_DN<7>
J 0
(-5690 5360);
DISPLAY 0.659574 (-5690 5360);
PAINT MONO (-5690 5360);
DISPLAY INVISIBLE (-5690 5360);
FORCEPROP 1 LASTPIN (-5700 5350) BN 7
J 2
(-5688 5358);
DISPLAY 0.489362 (-5688 5358);
PAINT MONO (-5688 5358);
FORCEPROP 2 LAST CDS_LIB mstr_standard
J 0
(-5750 5350);
DISPLAY INVISIBLE (-5750 5350);
FORCEPROP 1 LAST BODY_TYPE PLUMBING
J 2
(-5750 5400);
DISPLAY 0.872340 (-5750 5400);
PAINT GREEN (-5750 5400);
DISPLAY INVISIBLE (-5750 5400);
FORCEPROP 1 LAST HDL_TAP TRUE
J 2
(-6075 5225);
DISPLAY 0.872340 (-6075 5225);
DISPLAY INVISIBLE (-6075 5225);
FORCEPROP 1 LAST PATH I785
J 2
(-5748 5350);
DISPLAY 0.872340 (-5748 5350);
PAINT GREEN (-5748 5350);
DISPLAY INVISIBLE (-5748 5350);
FORCEADD TAP..1
R 2
(-5550 5050);
FORCEPROP 3 LASTPIN (-5500 5050) SIG_NAME M_A_CPU0_SB_DQS_DP<0>
J 0
(-5490 5060);
DISPLAY 0.659574 (-5490 5060);
PAINT MONO (-5490 5060);
DISPLAY INVISIBLE (-5490 5060);
FORCEPROP 1 LASTPIN (-5500 5050) BN 0
J 2
(-5488 5058);
DISPLAY 0.489362 (-5488 5058);
PAINT MONO (-5488 5058);
FORCEPROP 2 LAST CDS_LIB mstr_standard
J 0
(-5550 5050);
DISPLAY INVISIBLE (-5550 5050);
FORCEPROP 1 LAST BODY_TYPE PLUMBING
J 2
(-5550 5100);
DISPLAY 0.872340 (-5550 5100);
PAINT GREEN (-5550 5100);
DISPLAY INVISIBLE (-5550 5100);
FORCEPROP 1 LAST HDL_TAP TRUE
J 2
(-5875 4925);
DISPLAY 0.872340 (-5875 4925);
DISPLAY INVISIBLE (-5875 4925);
FORCEPROP 1 LAST PATH I786
J 2
(-5548 5050);
DISPLAY 0.872340 (-5548 5050);
PAINT GREEN (-5548 5050);
DISPLAY INVISIBLE (-5548 5050);
FORCEADD TAP..1
R 2
(-5550 4950);
FORCEPROP 3 LASTPIN (-5500 4950) SIG_NAME M_A_CPU0_SB_DQS_DP<1>
J 0
(-5490 4960);
DISPLAY 0.659574 (-5490 4960);
PAINT MONO (-5490 4960);
DISPLAY INVISIBLE (-5490 4960);
FORCEPROP 1 LASTPIN (-5500 4950) BN 1
J 2
(-5488 4958);
DISPLAY 0.489362 (-5488 4958);
PAINT MONO (-5488 4958);
FORCEPROP 2 LAST CDS_LIB mstr_standard
J 0
(-5550 4950);
DISPLAY INVISIBLE (-5550 4950);
FORCEPROP 1 LAST BODY_TYPE PLUMBING
J 2
(-5550 5000);
DISPLAY 0.872340 (-5550 5000);
PAINT GREEN (-5550 5000);
DISPLAY INVISIBLE (-5550 5000);
FORCEPROP 1 LAST HDL_TAP TRUE
J 2
(-5875 4825);
DISPLAY 0.872340 (-5875 4825);
DISPLAY INVISIBLE (-5875 4825);
FORCEPROP 1 LAST PATH I787
J 2
(-5548 4950);
DISPLAY 0.872340 (-5548 4950);
PAINT GREEN (-5548 4950);
DISPLAY INVISIBLE (-5548 4950);
FORCEADD TAP..1
R 2
(-5550 4750);
FORCEPROP 3 LASTPIN (-5500 4750) SIG_NAME M_A_CPU0_SB_DQS_DP<3>
J 0
(-5490 4760);
DISPLAY 0.659574 (-5490 4760);
PAINT MONO (-5490 4760);
DISPLAY INVISIBLE (-5490 4760);
FORCEPROP 1 LASTPIN (-5500 4750) BN 3
J 2
(-5488 4758);
DISPLAY 0.489362 (-5488 4758);
PAINT MONO (-5488 4758);
FORCEPROP 2 LAST CDS_LIB mstr_standard
J 0
(-5550 4750);
DISPLAY INVISIBLE (-5550 4750);
FORCEPROP 1 LAST BODY_TYPE PLUMBING
J 2
(-5550 4800);
DISPLAY 0.872340 (-5550 4800);
PAINT GREEN (-5550 4800);
DISPLAY INVISIBLE (-5550 4800);
FORCEPROP 1 LAST HDL_TAP TRUE
J 2
(-5875 4625);
DISPLAY 0.872340 (-5875 4625);
DISPLAY INVISIBLE (-5875 4625);
FORCEPROP 1 LAST PATH I788
J 2
(-5548 4750);
DISPLAY 0.872340 (-5548 4750);
PAINT GREEN (-5548 4750);
DISPLAY INVISIBLE (-5548 4750);
FORCEADD TAP..1
R 2
(-5550 4850);
FORCEPROP 3 LASTPIN (-5500 4850) SIG_NAME M_A_CPU0_SB_DQS_DP<2>
J 0
(-5490 4860);
DISPLAY 0.659574 (-5490 4860);
PAINT MONO (-5490 4860);
DISPLAY INVISIBLE (-5490 4860);
FORCEPROP 1 LASTPIN (-5500 4850) BN 2
J 2
(-5488 4858);
DISPLAY 0.489362 (-5488 4858);
PAINT MONO (-5488 4858);
FORCEPROP 2 LAST CDS_LIB mstr_standard
J 0
(-5550 4850);
DISPLAY INVISIBLE (-5550 4850);
FORCEPROP 1 LAST BODY_TYPE PLUMBING
J 2
(-5550 4900);
DISPLAY 0.872340 (-5550 4900);
PAINT GREEN (-5550 4900);
DISPLAY INVISIBLE (-5550 4900);
FORCEPROP 1 LAST HDL_TAP TRUE
J 2
(-5875 4725);
DISPLAY 0.872340 (-5875 4725);
DISPLAY INVISIBLE (-5875 4725);
FORCEPROP 1 LAST PATH I789
J 2
(-5548 4850);
DISPLAY 0.872340 (-5548 4850);
PAINT GREEN (-5548 4850);
DISPLAY INVISIBLE (-5548 4850);
FORCEADD TAP..1
R 2
(-5550 4650);
FORCEPROP 3 LASTPIN (-5500 4650) SIG_NAME M_A_CPU0_SB_DQS_DP<4>
J 0
(-5490 4660);
DISPLAY 0.659574 (-5490 4660);
PAINT MONO (-5490 4660);
DISPLAY INVISIBLE (-5490 4660);
FORCEPROP 1 LASTPIN (-5500 4650) BN 4
J 2
(-5488 4658);
DISPLAY 0.489362 (-5488 4658);
PAINT MONO (-5488 4658);
FORCEPROP 2 LAST CDS_LIB mstr_standard
J 0
(-5550 4650);
DISPLAY INVISIBLE (-5550 4650);
FORCEPROP 1 LAST BODY_TYPE PLUMBING
J 2
(-5550 4700);
DISPLAY 0.872340 (-5550 4700);
PAINT GREEN (-5550 4700);
DISPLAY INVISIBLE (-5550 4700);
FORCEPROP 1 LAST HDL_TAP TRUE
J 2
(-5875 4525);
DISPLAY 0.872340 (-5875 4525);
DISPLAY INVISIBLE (-5875 4525);
FORCEPROP 1 LAST PATH I790
J 2
(-5548 4650);
DISPLAY 0.872340 (-5548 4650);
PAINT GREEN (-5548 4650);
DISPLAY INVISIBLE (-5548 4650);
FORCEADD TAP..1
R 2
(-5550 4550);
FORCEPROP 3 LASTPIN (-5500 4550) SIG_NAME M_A_CPU0_SB_DQS_DP<5>
J 0
(-5490 4560);
DISPLAY 0.659574 (-5490 4560);
PAINT MONO (-5490 4560);
DISPLAY INVISIBLE (-5490 4560);
FORCEPROP 1 LASTPIN (-5500 4550) BN 5
J 2
(-5488 4558);
DISPLAY 0.489362 (-5488 4558);
PAINT MONO (-5488 4558);
FORCEPROP 2 LAST CDS_LIB mstr_standard
J 0
(-5550 4550);
DISPLAY INVISIBLE (-5550 4550);
FORCEPROP 1 LAST BODY_TYPE PLUMBING
J 2
(-5550 4600);
DISPLAY 0.872340 (-5550 4600);
PAINT GREEN (-5550 4600);
DISPLAY INVISIBLE (-5550 4600);
FORCEPROP 1 LAST HDL_TAP TRUE
J 2
(-5875 4425);
DISPLAY 0.872340 (-5875 4425);
DISPLAY INVISIBLE (-5875 4425);
FORCEPROP 1 LAST PATH I791
J 2
(-5548 4550);
DISPLAY 0.872340 (-5548 4550);
PAINT GREEN (-5548 4550);
DISPLAY INVISIBLE (-5548 4550);
FORCEADD TAP..1
R 2
(-5550 4450);
FORCEPROP 3 LASTPIN (-5500 4450) SIG_NAME M_A_CPU0_SB_DQS_DP<6>
J 0
(-5490 4460);
DISPLAY 0.659574 (-5490 4460);
PAINT MONO (-5490 4460);
DISPLAY INVISIBLE (-5490 4460);
FORCEPROP 1 LASTPIN (-5500 4450) BN 6
J 2
(-5488 4458);
DISPLAY 0.489362 (-5488 4458);
PAINT MONO (-5488 4458);
FORCEPROP 2 LAST CDS_LIB mstr_standard
J 0
(-5550 4450);
DISPLAY INVISIBLE (-5550 4450);
FORCEPROP 1 LAST BODY_TYPE PLUMBING
J 2
(-5550 4500);
DISPLAY 0.872340 (-5550 4500);
PAINT GREEN (-5550 4500);
DISPLAY INVISIBLE (-5550 4500);
FORCEPROP 1 LAST HDL_TAP TRUE
J 2
(-5875 4325);
DISPLAY 0.872340 (-5875 4325);
DISPLAY INVISIBLE (-5875 4325);
FORCEPROP 1 LAST PATH I792
J 2
(-5548 4450);
DISPLAY 0.872340 (-5548 4450);
PAINT GREEN (-5548 4450);
DISPLAY INVISIBLE (-5548 4450);
FORCEADD TAP..1
R 2
(-5550 4350);
FORCEPROP 3 LASTPIN (-5500 4350) SIG_NAME M_A_CPU0_SB_DQS_DP<7>
J 0
(-5490 4360);
DISPLAY 0.659574 (-5490 4360);
PAINT MONO (-5490 4360);
DISPLAY INVISIBLE (-5490 4360);
FORCEPROP 1 LASTPIN (-5500 4350) BN 7
J 2
(-5488 4358);
DISPLAY 0.489362 (-5488 4358);
PAINT MONO (-5488 4358);
FORCEPROP 2 LAST CDS_LIB mstr_standard
J 0
(-5550 4350);
DISPLAY INVISIBLE (-5550 4350);
FORCEPROP 1 LAST BODY_TYPE PLUMBING
J 2
(-5550 4400);
DISPLAY 0.872340 (-5550 4400);
PAINT GREEN (-5550 4400);
DISPLAY INVISIBLE (-5550 4400);
FORCEPROP 1 LAST HDL_TAP TRUE
J 2
(-5875 4225);
DISPLAY 0.872340 (-5875 4225);
DISPLAY INVISIBLE (-5875 4225);
FORCEPROP 1 LAST PATH I793
J 2
(-5548 4350);
DISPLAY 0.872340 (-5548 4350);
PAINT GREEN (-5548 4350);
DISPLAY INVISIBLE (-5548 4350);
FORCEADD TAP..1
R 2
(-5550 4250);
FORCEPROP 3 LASTPIN (-5500 4250) SIG_NAME M_A_CPU0_SB_DQS_DP<8>
J 0
(-5490 4260);
DISPLAY 0.659574 (-5490 4260);
PAINT MONO (-5490 4260);
DISPLAY INVISIBLE (-5490 4260);
FORCEPROP 1 LASTPIN (-5500 4250) BN 8
J 2
(-5488 4258);
DISPLAY 0.489362 (-5488 4258);
PAINT MONO (-5488 4258);
FORCEPROP 2 LAST CDS_LIB mstr_standard
J 0
(-5550 4250);
DISPLAY INVISIBLE (-5550 4250);
FORCEPROP 1 LAST BODY_TYPE PLUMBING
J 2
(-5550 4300);
DISPLAY 0.872340 (-5550 4300);
PAINT GREEN (-5550 4300);
DISPLAY INVISIBLE (-5550 4300);
FORCEPROP 1 LAST HDL_TAP TRUE
J 2
(-5875 4125);
DISPLAY 0.872340 (-5875 4125);
DISPLAY INVISIBLE (-5875 4125);
FORCEPROP 1 LAST PATH I794
J 2
(-5548 4250);
DISPLAY 0.872340 (-5548 4250);
PAINT GREEN (-5548 4250);
DISPLAY INVISIBLE (-5548 4250);
FORCEADD TAP..1
R 2
(-5550 4150);
FORCEPROP 3 LASTPIN (-5500 4150) SIG_NAME M_A_CPU0_SB_DQS_DP<9>
J 0
(-5490 4160);
DISPLAY 0.659574 (-5490 4160);
PAINT MONO (-5490 4160);
DISPLAY INVISIBLE (-5490 4160);
FORCEPROP 1 LASTPIN (-5500 4150) BN 9
J 2
(-5488 4158);
DISPLAY 0.489362 (-5488 4158);
PAINT MONO (-5488 4158);
FORCEPROP 2 LAST CDS_LIB mstr_standard
J 0
(-5550 4150);
DISPLAY INVISIBLE (-5550 4150);
FORCEPROP 1 LAST BODY_TYPE PLUMBING
J 2
(-5550 4200);
DISPLAY 0.872340 (-5550 4200);
PAINT GREEN (-5550 4200);
DISPLAY INVISIBLE (-5550 4200);
FORCEPROP 1 LAST HDL_TAP TRUE
J 2
(-5875 4025);
DISPLAY 0.872340 (-5875 4025);
DISPLAY INVISIBLE (-5875 4025);
FORCEPROP 1 LAST PATH I795
J 2
(-5548 4150);
DISPLAY 0.872340 (-5548 4150);
PAINT GREEN (-5548 4150);
DISPLAY INVISIBLE (-5548 4150);
FORCEADD TAP..1
R 2
(-5750 4900);
FORCEPROP 3 LASTPIN (-5700 4900) SIG_NAME M_A_CPU0_SB_DQS_DN<1>
J 0
(-5690 4910);
DISPLAY 0.659574 (-5690 4910);
PAINT MONO (-5690 4910);
DISPLAY INVISIBLE (-5690 4910);
FORCEPROP 1 LASTPIN (-5700 4900) BN 1
J 2
(-5688 4908);
DISPLAY 0.489362 (-5688 4908);
PAINT MONO (-5688 4908);
FORCEPROP 2 LAST CDS_LIB mstr_standard
J 0
(-5750 4900);
DISPLAY INVISIBLE (-5750 4900);
FORCEPROP 1 LAST BODY_TYPE PLUMBING
J 2
(-5750 4950);
DISPLAY 0.872340 (-5750 4950);
PAINT GREEN (-5750 4950);
DISPLAY INVISIBLE (-5750 4950);
FORCEPROP 1 LAST HDL_TAP TRUE
J 2
(-6075 4775);
DISPLAY 0.872340 (-6075 4775);
DISPLAY INVISIBLE (-6075 4775);
FORCEPROP 1 LAST PATH I796
J 2
(-5748 4900);
DISPLAY 0.872340 (-5748 4900);
PAINT GREEN (-5748 4900);
DISPLAY INVISIBLE (-5748 4900);
FORCEADD TAP..1
R 2
(-5750 5000);
FORCEPROP 3 LASTPIN (-5700 5000) SIG_NAME M_A_CPU0_SB_DQS_DN<0>
J 0
(-5690 5010);
DISPLAY 0.659574 (-5690 5010);
PAINT MONO (-5690 5010);
DISPLAY INVISIBLE (-5690 5010);
FORCEPROP 1 LASTPIN (-5700 5000) BN 0
J 2
(-5688 5008);
DISPLAY 0.489362 (-5688 5008);
PAINT MONO (-5688 5008);
FORCEPROP 2 LAST CDS_LIB mstr_standard
J 0
(-5750 5000);
DISPLAY INVISIBLE (-5750 5000);
FORCEPROP 1 LAST BODY_TYPE PLUMBING
J 2
(-5750 5050);
DISPLAY 0.872340 (-5750 5050);
PAINT GREEN (-5750 5050);
DISPLAY INVISIBLE (-5750 5050);
FORCEPROP 1 LAST HDL_TAP TRUE
J 2
(-6075 4875);
DISPLAY 0.872340 (-6075 4875);
DISPLAY INVISIBLE (-6075 4875);
FORCEPROP 1 LAST PATH I797
J 2
(-5748 5000);
DISPLAY 0.872340 (-5748 5000);
PAINT GREEN (-5748 5000);
DISPLAY INVISIBLE (-5748 5000);
FORCEADD TAP..1
R 2
(-5750 4700);
FORCEPROP 3 LASTPIN (-5700 4700) SIG_NAME M_A_CPU0_SB_DQS_DN<3>
J 0
(-5690 4710);
DISPLAY 0.659574 (-5690 4710);
PAINT MONO (-5690 4710);
DISPLAY INVISIBLE (-5690 4710);
FORCEPROP 1 LASTPIN (-5700 4700) BN 3
J 2
(-5688 4708);
DISPLAY 0.489362 (-5688 4708);
PAINT MONO (-5688 4708);
FORCEPROP 2 LAST CDS_LIB mstr_standard
J 0
(-5750 4700);
DISPLAY INVISIBLE (-5750 4700);
FORCEPROP 1 LAST BODY_TYPE PLUMBING
J 2
(-5750 4750);
DISPLAY 0.872340 (-5750 4750);
PAINT GREEN (-5750 4750);
DISPLAY INVISIBLE (-5750 4750);
FORCEPROP 1 LAST HDL_TAP TRUE
J 2
(-6075 4575);
DISPLAY 0.872340 (-6075 4575);
DISPLAY INVISIBLE (-6075 4575);
FORCEPROP 1 LAST PATH I798
J 2
(-5748 4700);
DISPLAY 0.872340 (-5748 4700);
PAINT GREEN (-5748 4700);
DISPLAY INVISIBLE (-5748 4700);
FORCEADD TAP..1
R 2
(-5750 4800);
FORCEPROP 3 LASTPIN (-5700 4800) SIG_NAME M_A_CPU0_SB_DQS_DN<2>
J 0
(-5690 4810);
DISPLAY 0.659574 (-5690 4810);
PAINT MONO (-5690 4810);
DISPLAY INVISIBLE (-5690 4810);
FORCEPROP 1 LASTPIN (-5700 4800) BN 2
J 2
(-5688 4808);
DISPLAY 0.489362 (-5688 4808);
PAINT MONO (-5688 4808);
FORCEPROP 2 LAST CDS_LIB mstr_standard
J 0
(-5750 4800);
DISPLAY INVISIBLE (-5750 4800);
FORCEPROP 1 LAST BODY_TYPE PLUMBING
J 2
(-5750 4850);
DISPLAY 0.872340 (-5750 4850);
PAINT GREEN (-5750 4850);
DISPLAY INVISIBLE (-5750 4850);
FORCEPROP 1 LAST HDL_TAP TRUE
J 2
(-6075 4675);
DISPLAY 0.872340 (-6075 4675);
DISPLAY INVISIBLE (-6075 4675);
FORCEPROP 1 LAST PATH I799
J 2
(-5748 4800);
DISPLAY 0.872340 (-5748 4800);
PAINT GREEN (-5748 4800);
DISPLAY INVISIBLE (-5748 4800);
FORCEADD TAP..1
R 2
(-5750 4600);
FORCEPROP 3 LASTPIN (-5700 4600) SIG_NAME M_A_CPU0_SB_DQS_DN<4>
J 0
(-5690 4610);
DISPLAY 0.659574 (-5690 4610);
PAINT MONO (-5690 4610);
DISPLAY INVISIBLE (-5690 4610);
FORCEPROP 1 LASTPIN (-5700 4600) BN 4
J 2
(-5688 4608);
DISPLAY 0.489362 (-5688 4608);
PAINT MONO (-5688 4608);
FORCEPROP 2 LAST CDS_LIB mstr_standard
J 0
(-5750 4600);
DISPLAY INVISIBLE (-5750 4600);
FORCEPROP 1 LAST BODY_TYPE PLUMBING
J 2
(-5750 4650);
DISPLAY 0.872340 (-5750 4650);
PAINT GREEN (-5750 4650);
DISPLAY INVISIBLE (-5750 4650);
FORCEPROP 1 LAST HDL_TAP TRUE
J 2
(-6075 4475);
DISPLAY 0.872340 (-6075 4475);
DISPLAY INVISIBLE (-6075 4475);
FORCEPROP 1 LAST PATH I800
J 2
(-5748 4600);
DISPLAY 0.872340 (-5748 4600);
PAINT GREEN (-5748 4600);
DISPLAY INVISIBLE (-5748 4600);
FORCEADD TAP..1
R 2
(-5750 4400);
FORCEPROP 3 LASTPIN (-5700 4400) SIG_NAME M_A_CPU0_SB_DQS_DN<6>
J 0
(-5690 4410);
DISPLAY 0.659574 (-5690 4410);
PAINT MONO (-5690 4410);
DISPLAY INVISIBLE (-5690 4410);
FORCEPROP 1 LASTPIN (-5700 4400) BN 6
J 2
(-5688 4408);
DISPLAY 0.489362 (-5688 4408);
PAINT MONO (-5688 4408);
FORCEPROP 2 LAST CDS_LIB mstr_standard
J 0
(-5750 4400);
DISPLAY INVISIBLE (-5750 4400);
FORCEPROP 1 LAST BODY_TYPE PLUMBING
J 2
(-5750 4450);
DISPLAY 0.872340 (-5750 4450);
PAINT GREEN (-5750 4450);
DISPLAY INVISIBLE (-5750 4450);
FORCEPROP 1 LAST HDL_TAP TRUE
J 2
(-6075 4275);
DISPLAY 0.872340 (-6075 4275);
DISPLAY INVISIBLE (-6075 4275);
FORCEPROP 1 LAST PATH I801
J 2
(-5748 4400);
DISPLAY 0.872340 (-5748 4400);
PAINT GREEN (-5748 4400);
DISPLAY INVISIBLE (-5748 4400);
FORCEADD TAP..1
R 2
(-5750 4500);
FORCEPROP 3 LASTPIN (-5700 4500) SIG_NAME M_A_CPU0_SB_DQS_DN<5>
J 0
(-5690 4510);
DISPLAY 0.659574 (-5690 4510);
PAINT MONO (-5690 4510);
DISPLAY INVISIBLE (-5690 4510);
FORCEPROP 1 LASTPIN (-5700 4500) BN 5
J 2
(-5688 4508);
DISPLAY 0.489362 (-5688 4508);
PAINT MONO (-5688 4508);
FORCEPROP 2 LAST CDS_LIB mstr_standard
J 0
(-5750 4500);
DISPLAY INVISIBLE (-5750 4500);
FORCEPROP 1 LAST BODY_TYPE PLUMBING
J 2
(-5750 4550);
DISPLAY 0.872340 (-5750 4550);
PAINT GREEN (-5750 4550);
DISPLAY INVISIBLE (-5750 4550);
FORCEPROP 1 LAST HDL_TAP TRUE
J 2
(-6075 4375);
DISPLAY 0.872340 (-6075 4375);
DISPLAY INVISIBLE (-6075 4375);
FORCEPROP 1 LAST PATH I802
J 2
(-5748 4500);
DISPLAY 0.872340 (-5748 4500);
PAINT GREEN (-5748 4500);
DISPLAY INVISIBLE (-5748 4500);
FORCEADD TAP..1
R 2
(-5750 4100);
FORCEPROP 3 LASTPIN (-5700 4100) SIG_NAME M_A_CPU0_SB_DQS_DN<9>
J 0
(-5690 4110);
DISPLAY 0.659574 (-5690 4110);
PAINT MONO (-5690 4110);
DISPLAY INVISIBLE (-5690 4110);
FORCEPROP 1 LASTPIN (-5700 4100) BN 9
J 2
(-5688 4108);
DISPLAY 0.489362 (-5688 4108);
PAINT MONO (-5688 4108);
FORCEPROP 2 LAST CDS_LIB mstr_standard
J 0
(-5750 4100);
DISPLAY INVISIBLE (-5750 4100);
FORCEPROP 1 LAST BODY_TYPE PLUMBING
J 2
(-5750 4150);
DISPLAY 0.872340 (-5750 4150);
PAINT GREEN (-5750 4150);
DISPLAY INVISIBLE (-5750 4150);
FORCEPROP 1 LAST HDL_TAP TRUE
J 2
(-6075 3975);
DISPLAY 0.872340 (-6075 3975);
DISPLAY INVISIBLE (-6075 3975);
FORCEPROP 1 LAST PATH I803
J 2
(-5748 4100);
DISPLAY 0.872340 (-5748 4100);
PAINT GREEN (-5748 4100);
DISPLAY INVISIBLE (-5748 4100);
FORCEADD TAP..1
R 2
(-5750 4200);
FORCEPROP 3 LASTPIN (-5700 4200) SIG_NAME M_A_CPU0_SB_DQS_DN<8>
J 0
(-5690 4210);
DISPLAY 0.659574 (-5690 4210);
PAINT MONO (-5690 4210);
DISPLAY INVISIBLE (-5690 4210);
FORCEPROP 1 LASTPIN (-5700 4200) BN 8
J 2
(-5688 4208);
DISPLAY 0.489362 (-5688 4208);
PAINT MONO (-5688 4208);
FORCEPROP 2 LAST CDS_LIB mstr_standard
J 0
(-5750 4200);
DISPLAY INVISIBLE (-5750 4200);
FORCEPROP 1 LAST BODY_TYPE PLUMBING
J 2
(-5750 4250);
DISPLAY 0.872340 (-5750 4250);
PAINT GREEN (-5750 4250);
DISPLAY INVISIBLE (-5750 4250);
FORCEPROP 1 LAST HDL_TAP TRUE
J 2
(-6075 4075);
DISPLAY 0.872340 (-6075 4075);
DISPLAY INVISIBLE (-6075 4075);
FORCEPROP 1 LAST PATH I804
J 2
(-5748 4200);
DISPLAY 0.872340 (-5748 4200);
PAINT GREEN (-5748 4200);
DISPLAY INVISIBLE (-5748 4200);
FORCEADD TAP..1
R 2
(-5750 4300);
FORCEPROP 3 LASTPIN (-5700 4300) SIG_NAME M_A_CPU0_SB_DQS_DN<7>
J 0
(-5690 4310);
DISPLAY 0.659574 (-5690 4310);
PAINT MONO (-5690 4310);
DISPLAY INVISIBLE (-5690 4310);
FORCEPROP 1 LASTPIN (-5700 4300) BN 7
J 2
(-5688 4308);
DISPLAY 0.489362 (-5688 4308);
PAINT MONO (-5688 4308);
FORCEPROP 2 LAST CDS_LIB mstr_standard
J 0
(-5750 4300);
DISPLAY INVISIBLE (-5750 4300);
FORCEPROP 1 LAST BODY_TYPE PLUMBING
J 2
(-5750 4350);
DISPLAY 0.872340 (-5750 4350);
PAINT GREEN (-5750 4350);
DISPLAY INVISIBLE (-5750 4350);
FORCEPROP 1 LAST HDL_TAP TRUE
J 2
(-6075 4175);
DISPLAY 0.872340 (-6075 4175);
DISPLAY INVISIBLE (-6075 4175);
FORCEPROP 1 LAST PATH I805
J 2
(-5748 4300);
DISPLAY 0.872340 (-5748 4300);
PAINT GREEN (-5748 4300);
DISPLAY INVISIBLE (-5748 4300);
FORCEADD OFFPAGE..3
R 2
(-6450 6075);
FORCEPROP 2 LAST $XR0 86 
J 0
(-6729 6075);
DISPLAY 0.638298 (-6729 6075);
PAINT MONO (-6729 6075);
FORCEPROP 2 LAST CDS_LIB standard
J 0
(-6450 6075);
DISPLAY INVISIBLE (-6450 6075);
FORCEPROP 1 LAST OFFPAGE TRUE
J 2
(-6775 5950);
DISPLAY 0.872340 (-6775 5950);
PAINT GREEN (-6775 5950);
DISPLAY INVISIBLE (-6775 5950);
FORCEPROP 1 LAST COMMENT_BODY TRUE
J 2
(-6400 5975);
DISPLAY 0.872340 (-6400 5975);
PAINT GREEN (-6400 5975);
DISPLAY INVISIBLE (-6400 5975);
FORCEPROP 2 LAST PATH I806
J 0
(-6750 6125);
DISPLAY 1.021277 (-6750 6125);
DISPLAY INVISIBLE (-6750 6125);
FORCEADD OFFPAGE..3
R 2
(-6450 6125);
FORCEPROP 2 LAST $XR0 86 
J 0
(-6729 6125);
DISPLAY 0.638298 (-6729 6125);
PAINT MONO (-6729 6125);
FORCEPROP 2 LAST CDS_LIB standard
J 0
(-6450 6125);
DISPLAY INVISIBLE (-6450 6125);
FORCEPROP 1 LAST OFFPAGE TRUE
J 2
(-6775 6000);
DISPLAY 0.872340 (-6775 6000);
PAINT GREEN (-6775 6000);
DISPLAY INVISIBLE (-6775 6000);
FORCEPROP 1 LAST COMMENT_BODY TRUE
J 2
(-6400 6025);
DISPLAY 0.872340 (-6400 6025);
PAINT GREEN (-6400 6025);
DISPLAY INVISIBLE (-6400 6025);
FORCEPROP 2 LAST PATH I807
J 0
(-6750 6175);
DISPLAY 1.021277 (-6750 6175);
DISPLAY INVISIBLE (-6750 6175);
FORCEADD OFFPAGE..3
R 2
(-6450 5025);
FORCEPROP 2 LASTPIN (-6400 5025) SIG_NAME M_A_CPU0_SB_DQS_DN<9:0>
J 0
(-6435 5035);
DISPLAY 0.489362 (-6435 5035);
FORCEPROP 2 LAST $XR0 86 
J 0
(-6729 5025);
DISPLAY 0.638298 (-6729 5025);
PAINT MONO (-6729 5025);
FORCEPROP 2 LAST CDS_LIB standard
J 0
(-6450 5025);
DISPLAY INVISIBLE (-6450 5025);
FORCEPROP 1 LAST OFFPAGE TRUE
J 2
(-6775 4900);
DISPLAY 0.872340 (-6775 4900);
PAINT GREEN (-6775 4900);
DISPLAY INVISIBLE (-6775 4900);
FORCEPROP 1 LAST COMMENT_BODY TRUE
J 2
(-6400 4925);
DISPLAY 0.872340 (-6400 4925);
PAINT GREEN (-6400 4925);
DISPLAY INVISIBLE (-6400 4925);
FORCEPROP 2 LAST PATH I808
J 0
(-6750 5075);
DISPLAY 1.021277 (-6750 5075);
DISPLAY INVISIBLE (-6750 5075);
FORCEADD OFFPAGE..3
R 2
(-6450 5075);
FORCEPROP 2 LAST $XR0 86 
J 0
(-6729 5075);
DISPLAY 0.638298 (-6729 5075);
PAINT MONO (-6729 5075);
FORCEPROP 2 LAST CDS_LIB standard
J 0
(-6450 5075);
DISPLAY INVISIBLE (-6450 5075);
FORCEPROP 1 LAST OFFPAGE TRUE
J 2
(-6775 4950);
DISPLAY 0.872340 (-6775 4950);
PAINT GREEN (-6775 4950);
DISPLAY INVISIBLE (-6775 4950);
FORCEPROP 1 LAST COMMENT_BODY TRUE
J 2
(-6400 4975);
DISPLAY 0.872340 (-6400 4975);
PAINT GREEN (-6400 4975);
DISPLAY INVISIBLE (-6400 4975);
FORCEPROP 2 LAST PATH I809
J 0
(-6750 5125);
DISPLAY 1.021277 (-6750 5125);
DISPLAY INVISIBLE (-6750 5125);
FORCEADD TAP..1
R 2
(-5700 3900);
FORCEPROP 3 LASTPIN (-5650 3900) SIG_NAME M_A_CPU0_SA_CA<1>
J 0
(-5640 3910);
DISPLAY 0.659574 (-5640 3910);
PAINT MONO (-5640 3910);
DISPLAY INVISIBLE (-5640 3910);
FORCEPROP 1 LASTPIN (-5650 3900) BN 1
J 2
(-5638 3908);
DISPLAY 0.489362 (-5638 3908);
PAINT MONO (-5638 3908);
FORCEPROP 2 LAST CDS_LIB mstr_standard
J 0
(-5700 3900);
DISPLAY INVISIBLE (-5700 3900);
FORCEPROP 1 LAST BODY_TYPE PLUMBING
J 2
(-5700 3950);
DISPLAY 0.872340 (-5700 3950);
PAINT GREEN (-5700 3950);
DISPLAY INVISIBLE (-5700 3950);
FORCEPROP 1 LAST HDL_TAP TRUE
J 2
(-6025 3775);
DISPLAY 0.872340 (-6025 3775);
DISPLAY INVISIBLE (-6025 3775);
FORCEPROP 1 LAST PATH I810
J 2
(-5698 3900);
DISPLAY 0.872340 (-5698 3900);
PAINT GREEN (-5698 3900);
DISPLAY INVISIBLE (-5698 3900);
FORCEADD TAP..1
R 2
(-5700 3950);
FORCEPROP 3 LASTPIN (-5650 3950) SIG_NAME M_A_CPU0_SA_CA<0>
J 0
(-5640 3960);
DISPLAY 0.659574 (-5640 3960);
PAINT MONO (-5640 3960);
DISPLAY INVISIBLE (-5640 3960);
FORCEPROP 1 LASTPIN (-5650 3950) BN 0
J 2
(-5638 3958);
DISPLAY 0.489362 (-5638 3958);
PAINT MONO (-5638 3958);
FORCEPROP 2 LAST CDS_LIB mstr_standard
J 0
(-5700 3950);
DISPLAY INVISIBLE (-5700 3950);
FORCEPROP 1 LAST BODY_TYPE PLUMBING
J 2
(-5700 4000);
DISPLAY 0.872340 (-5700 4000);
PAINT GREEN (-5700 4000);
DISPLAY INVISIBLE (-5700 4000);
FORCEPROP 1 LAST HDL_TAP TRUE
J 2
(-6025 3825);
DISPLAY 0.872340 (-6025 3825);
DISPLAY INVISIBLE (-6025 3825);
FORCEPROP 1 LAST PATH I811
J 2
(-5698 3950);
DISPLAY 0.872340 (-5698 3950);
PAINT GREEN (-5698 3950);
DISPLAY INVISIBLE (-5698 3950);
FORCEADD TAP..1
R 2
(-5700 3850);
FORCEPROP 3 LASTPIN (-5650 3850) SIG_NAME M_A_CPU0_SA_CA<2>
J 0
(-5640 3860);
DISPLAY 0.659574 (-5640 3860);
PAINT MONO (-5640 3860);
DISPLAY INVISIBLE (-5640 3860);
FORCEPROP 1 LASTPIN (-5650 3850) BN 2
J 2
(-5638 3858);
DISPLAY 0.489362 (-5638 3858);
PAINT MONO (-5638 3858);
FORCEPROP 2 LAST CDS_LIB mstr_standard
J 0
(-5700 3850);
DISPLAY INVISIBLE (-5700 3850);
FORCEPROP 1 LAST BODY_TYPE PLUMBING
J 2
(-5700 3900);
DISPLAY 0.872340 (-5700 3900);
PAINT GREEN (-5700 3900);
DISPLAY INVISIBLE (-5700 3900);
FORCEPROP 1 LAST HDL_TAP TRUE
J 2
(-6025 3725);
DISPLAY 0.872340 (-6025 3725);
DISPLAY INVISIBLE (-6025 3725);
FORCEPROP 1 LAST PATH I812
J 2
(-5698 3850);
DISPLAY 0.872340 (-5698 3850);
PAINT GREEN (-5698 3850);
DISPLAY INVISIBLE (-5698 3850);
FORCEADD TAP..1
R 2
(-5700 3750);
FORCEPROP 3 LASTPIN (-5650 3750) SIG_NAME M_A_CPU0_SA_CA<4>
J 0
(-5640 3760);
DISPLAY 0.659574 (-5640 3760);
PAINT MONO (-5640 3760);
DISPLAY INVISIBLE (-5640 3760);
FORCEPROP 1 LASTPIN (-5650 3750) BN 4
J 2
(-5638 3758);
DISPLAY 0.489362 (-5638 3758);
PAINT MONO (-5638 3758);
FORCEPROP 2 LAST CDS_LIB mstr_standard
J 0
(-5700 3750);
DISPLAY INVISIBLE (-5700 3750);
FORCEPROP 1 LAST BODY_TYPE PLUMBING
J 2
(-5700 3800);
DISPLAY 0.872340 (-5700 3800);
PAINT GREEN (-5700 3800);
DISPLAY INVISIBLE (-5700 3800);
FORCEPROP 1 LAST HDL_TAP TRUE
J 2
(-6025 3625);
DISPLAY 0.872340 (-6025 3625);
DISPLAY INVISIBLE (-6025 3625);
FORCEPROP 1 LAST PATH I813
J 2
(-5698 3750);
DISPLAY 0.872340 (-5698 3750);
PAINT GREEN (-5698 3750);
DISPLAY INVISIBLE (-5698 3750);
FORCEADD TAP..1
R 2
(-5700 3800);
FORCEPROP 3 LASTPIN (-5650 3800) SIG_NAME M_A_CPU0_SA_CA<3>
J 0
(-5640 3810);
DISPLAY 0.659574 (-5640 3810);
PAINT MONO (-5640 3810);
DISPLAY INVISIBLE (-5640 3810);
FORCEPROP 1 LASTPIN (-5650 3800) BN 3
J 2
(-5638 3808);
DISPLAY 0.489362 (-5638 3808);
PAINT MONO (-5638 3808);
FORCEPROP 2 LAST CDS_LIB mstr_standard
J 0
(-5700 3800);
DISPLAY INVISIBLE (-5700 3800);
FORCEPROP 1 LAST BODY_TYPE PLUMBING
J 2
(-5700 3850);
DISPLAY 0.872340 (-5700 3850);
PAINT GREEN (-5700 3850);
DISPLAY INVISIBLE (-5700 3850);
FORCEPROP 1 LAST HDL_TAP TRUE
J 2
(-6025 3675);
DISPLAY 0.872340 (-6025 3675);
DISPLAY INVISIBLE (-6025 3675);
FORCEPROP 1 LAST PATH I814
J 2
(-5698 3800);
DISPLAY 0.872340 (-5698 3800);
PAINT GREEN (-5698 3800);
DISPLAY INVISIBLE (-5698 3800);
FORCEADD TAP..1
R 2
(-5700 3650);
FORCEPROP 3 LASTPIN (-5650 3650) SIG_NAME M_A_CPU0_SA_CA<6>
J 0
(-5640 3660);
DISPLAY 0.659574 (-5640 3660);
PAINT MONO (-5640 3660);
DISPLAY INVISIBLE (-5640 3660);
FORCEPROP 1 LASTPIN (-5650 3650) BN 6
J 2
(-5638 3658);
DISPLAY 0.489362 (-5638 3658);
PAINT MONO (-5638 3658);
FORCEPROP 2 LAST CDS_LIB mstr_standard
J 0
(-5700 3650);
DISPLAY INVISIBLE (-5700 3650);
FORCEPROP 1 LAST BODY_TYPE PLUMBING
J 2
(-5700 3700);
DISPLAY 0.872340 (-5700 3700);
PAINT GREEN (-5700 3700);
DISPLAY INVISIBLE (-5700 3700);
FORCEPROP 1 LAST HDL_TAP TRUE
J 2
(-6025 3525);
DISPLAY 0.872340 (-6025 3525);
DISPLAY INVISIBLE (-6025 3525);
FORCEPROP 1 LAST PATH I815
J 2
(-5698 3650);
DISPLAY 0.872340 (-5698 3650);
PAINT GREEN (-5698 3650);
DISPLAY INVISIBLE (-5698 3650);
FORCEADD TAP..1
R 2
(-5700 3700);
FORCEPROP 3 LASTPIN (-5650 3700) SIG_NAME M_A_CPU0_SA_CA<5>
J 0
(-5640 3710);
DISPLAY 0.659574 (-5640 3710);
PAINT MONO (-5640 3710);
DISPLAY INVISIBLE (-5640 3710);
FORCEPROP 1 LASTPIN (-5650 3700) BN 5
J 2
(-5638 3708);
DISPLAY 0.489362 (-5638 3708);
PAINT MONO (-5638 3708);
FORCEPROP 2 LAST CDS_LIB mstr_standard
J 0
(-5700 3700);
DISPLAY INVISIBLE (-5700 3700);
FORCEPROP 1 LAST BODY_TYPE PLUMBING
J 2
(-5700 3750);
DISPLAY 0.872340 (-5700 3750);
PAINT GREEN (-5700 3750);
DISPLAY INVISIBLE (-5700 3750);
FORCEPROP 1 LAST HDL_TAP TRUE
J 2
(-6025 3575);
DISPLAY 0.872340 (-6025 3575);
DISPLAY INVISIBLE (-6025 3575);
FORCEPROP 1 LAST PATH I816
J 2
(-5698 3700);
DISPLAY 0.872340 (-5698 3700);
PAINT GREEN (-5698 3700);
DISPLAY INVISIBLE (-5698 3700);
FORCEADD TAP..1
R 2
(-5700 3500);
FORCEPROP 3 LASTPIN (-5650 3500) SIG_NAME M_A_CPU0_SB_CA<1>
J 0
(-5640 3510);
DISPLAY 0.659574 (-5640 3510);
PAINT MONO (-5640 3510);
DISPLAY INVISIBLE (-5640 3510);
FORCEPROP 1 LASTPIN (-5650 3500) BN 1
J 2
(-5638 3508);
DISPLAY 0.489362 (-5638 3508);
PAINT MONO (-5638 3508);
FORCEPROP 2 LAST CDS_LIB mstr_standard
J 0
(-5700 3500);
DISPLAY INVISIBLE (-5700 3500);
FORCEPROP 1 LAST BODY_TYPE PLUMBING
J 2
(-5700 3550);
DISPLAY 0.872340 (-5700 3550);
PAINT GREEN (-5700 3550);
DISPLAY INVISIBLE (-5700 3550);
FORCEPROP 1 LAST HDL_TAP TRUE
J 2
(-6025 3375);
DISPLAY 0.872340 (-6025 3375);
DISPLAY INVISIBLE (-6025 3375);
FORCEPROP 1 LAST PATH I817
J 2
(-5698 3500);
DISPLAY 0.872340 (-5698 3500);
PAINT GREEN (-5698 3500);
DISPLAY INVISIBLE (-5698 3500);
FORCEADD TAP..1
R 2
(-5700 3550);
FORCEPROP 3 LASTPIN (-5650 3550) SIG_NAME M_A_CPU0_SB_CA<0>
J 0
(-5640 3560);
DISPLAY 0.659574 (-5640 3560);
PAINT MONO (-5640 3560);
DISPLAY INVISIBLE (-5640 3560);
FORCEPROP 1 LASTPIN (-5650 3550) BN 0
J 2
(-5638 3558);
DISPLAY 0.489362 (-5638 3558);
PAINT MONO (-5638 3558);
FORCEPROP 2 LAST CDS_LIB mstr_standard
J 0
(-5700 3550);
DISPLAY INVISIBLE (-5700 3550);
FORCEPROP 1 LAST BODY_TYPE PLUMBING
J 2
(-5700 3600);
DISPLAY 0.872340 (-5700 3600);
PAINT GREEN (-5700 3600);
DISPLAY INVISIBLE (-5700 3600);
FORCEPROP 1 LAST HDL_TAP TRUE
J 2
(-6025 3425);
DISPLAY 0.872340 (-6025 3425);
DISPLAY INVISIBLE (-6025 3425);
FORCEPROP 1 LAST PATH I818
J 2
(-5698 3550);
DISPLAY 0.872340 (-5698 3550);
PAINT GREEN (-5698 3550);
DISPLAY INVISIBLE (-5698 3550);
FORCEADD TAP..1
R 2
(-5700 3350);
FORCEPROP 3 LASTPIN (-5650 3350) SIG_NAME M_A_CPU0_SB_CA<4>
J 0
(-5640 3360);
DISPLAY 0.659574 (-5640 3360);
PAINT MONO (-5640 3360);
DISPLAY INVISIBLE (-5640 3360);
FORCEPROP 1 LASTPIN (-5650 3350) BN 4
J 2
(-5638 3358);
DISPLAY 0.489362 (-5638 3358);
PAINT MONO (-5638 3358);
FORCEPROP 2 LAST CDS_LIB mstr_standard
J 0
(-5700 3350);
DISPLAY INVISIBLE (-5700 3350);
FORCEPROP 1 LAST BODY_TYPE PLUMBING
J 2
(-5700 3400);
DISPLAY 0.872340 (-5700 3400);
PAINT GREEN (-5700 3400);
DISPLAY INVISIBLE (-5700 3400);
FORCEPROP 1 LAST HDL_TAP TRUE
J 2
(-6025 3225);
DISPLAY 0.872340 (-6025 3225);
DISPLAY INVISIBLE (-6025 3225);
FORCEPROP 1 LAST PATH I819
J 2
(-5698 3350);
DISPLAY 0.872340 (-5698 3350);
PAINT GREEN (-5698 3350);
DISPLAY INVISIBLE (-5698 3350);
FORCEADD TAP..1
R 2
(-5700 3400);
FORCEPROP 3 LASTPIN (-5650 3400) SIG_NAME M_A_CPU0_SB_CA<3>
J 0
(-5640 3410);
DISPLAY 0.659574 (-5640 3410);
PAINT MONO (-5640 3410);
DISPLAY INVISIBLE (-5640 3410);
FORCEPROP 1 LASTPIN (-5650 3400) BN 3
J 2
(-5638 3408);
DISPLAY 0.489362 (-5638 3408);
PAINT MONO (-5638 3408);
FORCEPROP 2 LAST CDS_LIB mstr_standard
J 0
(-5700 3400);
DISPLAY INVISIBLE (-5700 3400);
FORCEPROP 1 LAST BODY_TYPE PLUMBING
J 2
(-5700 3450);
DISPLAY 0.872340 (-5700 3450);
PAINT GREEN (-5700 3450);
DISPLAY INVISIBLE (-5700 3450);
FORCEPROP 1 LAST HDL_TAP TRUE
J 2
(-6025 3275);
DISPLAY 0.872340 (-6025 3275);
DISPLAY INVISIBLE (-6025 3275);
FORCEPROP 1 LAST PATH I820
J 2
(-5698 3400);
DISPLAY 0.872340 (-5698 3400);
PAINT GREEN (-5698 3400);
DISPLAY INVISIBLE (-5698 3400);
FORCEADD TAP..1
R 2
(-5700 3450);
FORCEPROP 3 LASTPIN (-5650 3450) SIG_NAME M_A_CPU0_SB_CA<2>
J 0
(-5640 3460);
DISPLAY 0.659574 (-5640 3460);
PAINT MONO (-5640 3460);
DISPLAY INVISIBLE (-5640 3460);
FORCEPROP 1 LASTPIN (-5650 3450) BN 2
J 2
(-5638 3458);
DISPLAY 0.489362 (-5638 3458);
PAINT MONO (-5638 3458);
FORCEPROP 2 LAST CDS_LIB mstr_standard
J 0
(-5700 3450);
DISPLAY INVISIBLE (-5700 3450);
FORCEPROP 1 LAST BODY_TYPE PLUMBING
J 2
(-5700 3500);
DISPLAY 0.872340 (-5700 3500);
PAINT GREEN (-5700 3500);
DISPLAY INVISIBLE (-5700 3500);
FORCEPROP 1 LAST HDL_TAP TRUE
J 2
(-6025 3325);
DISPLAY 0.872340 (-6025 3325);
DISPLAY INVISIBLE (-6025 3325);
FORCEPROP 1 LAST PATH I821
J 2
(-5698 3450);
DISPLAY 0.872340 (-5698 3450);
PAINT GREEN (-5698 3450);
DISPLAY INVISIBLE (-5698 3450);
FORCEADD TAP..1
R 2
(-5700 3250);
FORCEPROP 3 LASTPIN (-5650 3250) SIG_NAME M_A_CPU0_SB_CA<6>
J 0
(-5640 3260);
DISPLAY 0.659574 (-5640 3260);
PAINT MONO (-5640 3260);
DISPLAY INVISIBLE (-5640 3260);
FORCEPROP 1 LASTPIN (-5650 3250) BN 6
J 2
(-5638 3258);
DISPLAY 0.489362 (-5638 3258);
PAINT MONO (-5638 3258);
FORCEPROP 2 LAST CDS_LIB mstr_standard
J 0
(-5700 3250);
DISPLAY INVISIBLE (-5700 3250);
FORCEPROP 1 LAST BODY_TYPE PLUMBING
J 2
(-5700 3300);
DISPLAY 0.872340 (-5700 3300);
PAINT GREEN (-5700 3300);
DISPLAY INVISIBLE (-5700 3300);
FORCEPROP 1 LAST HDL_TAP TRUE
J 2
(-6025 3125);
DISPLAY 0.872340 (-6025 3125);
DISPLAY INVISIBLE (-6025 3125);
FORCEPROP 1 LAST PATH I822
J 2
(-5698 3250);
DISPLAY 0.872340 (-5698 3250);
PAINT GREEN (-5698 3250);
DISPLAY INVISIBLE (-5698 3250);
FORCEADD TAP..1
R 2
(-5700 3300);
FORCEPROP 3 LASTPIN (-5650 3300) SIG_NAME M_A_CPU0_SB_CA<5>
J 0
(-5640 3310);
DISPLAY 0.659574 (-5640 3310);
PAINT MONO (-5640 3310);
DISPLAY INVISIBLE (-5640 3310);
FORCEPROP 1 LASTPIN (-5650 3300) BN 5
J 2
(-5638 3308);
DISPLAY 0.489362 (-5638 3308);
PAINT MONO (-5638 3308);
FORCEPROP 2 LAST CDS_LIB mstr_standard
J 0
(-5700 3300);
DISPLAY INVISIBLE (-5700 3300);
FORCEPROP 1 LAST BODY_TYPE PLUMBING
J 2
(-5700 3350);
DISPLAY 0.872340 (-5700 3350);
PAINT GREEN (-5700 3350);
DISPLAY INVISIBLE (-5700 3350);
FORCEPROP 1 LAST HDL_TAP TRUE
J 2
(-6025 3175);
DISPLAY 0.872340 (-6025 3175);
DISPLAY INVISIBLE (-6025 3175);
FORCEPROP 1 LAST PATH I823
J 2
(-5698 3300);
DISPLAY 0.872340 (-5698 3300);
PAINT GREEN (-5698 3300);
DISPLAY INVISIBLE (-5698 3300);
FORCEADD OFFPAGE..2
R 2
(-6300 3975);
FORCEPROP 2 LAST $XR0 86 
J 0
(-6524 3975);
DISPLAY 0.638298 (-6524 3975);
PAINT MONO (-6524 3975);
FORCEPROP 2 LAST CDS_LIB standard
J 0
(-6300 3975);
DISPLAY INVISIBLE (-6300 3975);
FORCEPROP 1 LAST OFFPAGE TRUE
J 2
(-6625 3850);
DISPLAY 0.872340 (-6625 3850);
PAINT GREEN (-6625 3850);
DISPLAY INVISIBLE (-6625 3850);
FORCEPROP 1 LAST COMMENT_BODY TRUE
J 2
(-6255 3880);
DISPLAY 0.872340 (-6255 3880);
PAINT GREEN (-6255 3880);
DISPLAY INVISIBLE (-6255 3880);
FORCEPROP 2 LAST PATH I824
J 0
(-6550 4025);
DISPLAY 1.021277 (-6550 4025);
DISPLAY INVISIBLE (-6550 4025);
FORCEADD OFFPAGE..2
R 2
(-6300 3575);
FORCEPROP 2 LASTPIN (-6250 3575) SIG_NAME M_A_CPU0_SB_CA<6:0>
J 0
(-6285 3585);
DISPLAY 0.489362 (-6285 3585);
FORCEPROP 2 LAST $XR0 86 
J 0
(-6524 3575);
DISPLAY 0.638298 (-6524 3575);
PAINT MONO (-6524 3575);
FORCEPROP 2 LAST CDS_LIB standard
J 0
(-6300 3575);
DISPLAY INVISIBLE (-6300 3575);
FORCEPROP 1 LAST OFFPAGE TRUE
J 2
(-6625 3450);
DISPLAY 0.872340 (-6625 3450);
PAINT GREEN (-6625 3450);
DISPLAY INVISIBLE (-6625 3450);
FORCEPROP 1 LAST COMMENT_BODY TRUE
J 2
(-6255 3480);
DISPLAY 0.872340 (-6255 3480);
PAINT GREEN (-6255 3480);
DISPLAY INVISIBLE (-6255 3480);
FORCEPROP 2 LAST PATH I825
J 0
(-6550 3625);
DISPLAY 1.021277 (-6550 3625);
DISPLAY INVISIBLE (-6550 3625);
FORCEADD OFFPAGE..2
R 2
(-6300 3100);
FORCEPROP 2 LAST $XR0 86 
J 0
(-6524 3100);
DISPLAY 0.638298 (-6524 3100);
PAINT MONO (-6524 3100);
FORCEPROP 2 LAST CDS_LIB standard
J 0
(-6300 3100);
DISPLAY INVISIBLE (-6300 3100);
FORCEPROP 1 LAST OFFPAGE TRUE
J 2
(-6625 2975);
DISPLAY 0.872340 (-6625 2975);
PAINT GREEN (-6625 2975);
DISPLAY INVISIBLE (-6625 2975);
FORCEPROP 1 LAST COMMENT_BODY TRUE
J 2
(-6255 3005);
DISPLAY 0.872340 (-6255 3005);
PAINT GREEN (-6255 3005);
DISPLAY INVISIBLE (-6255 3005);
FORCEPROP 2 LAST PATH I826
J 0
(-6550 3150);
DISPLAY 1.021277 (-6550 3150);
DISPLAY INVISIBLE (-6550 3150);
FORCEADD OFFPAGE..2
R 2
(-6300 3050);
FORCEPROP 2 LAST $XR0 86 
J 0
(-6524 3050);
DISPLAY 0.638298 (-6524 3050);
PAINT MONO (-6524 3050);
FORCEPROP 2 LAST CDS_LIB standard
J 0
(-6300 3050);
DISPLAY INVISIBLE (-6300 3050);
FORCEPROP 1 LAST OFFPAGE TRUE
J 2
(-6625 2925);
DISPLAY 0.872340 (-6625 2925);
PAINT GREEN (-6625 2925);
DISPLAY INVISIBLE (-6625 2925);
FORCEPROP 1 LAST COMMENT_BODY TRUE
J 2
(-6255 2955);
DISPLAY 0.872340 (-6255 2955);
PAINT GREEN (-6255 2955);
DISPLAY INVISIBLE (-6255 2955);
FORCEPROP 2 LAST PATH I827
J 0
(-6550 3100);
DISPLAY 1.021277 (-6550 3100);
DISPLAY INVISIBLE (-6550 3100);
FORCEADD OFFPAGE..2
R 2
(-6300 2950);
FORCEPROP 2 LAST $XR0 86 
J 0
(-6524 2950);
DISPLAY 0.638298 (-6524 2950);
PAINT MONO (-6524 2950);
FORCEPROP 2 LAST CDS_LIB standard
J 0
(-6300 2950);
DISPLAY INVISIBLE (-6300 2950);
FORCEPROP 1 LAST OFFPAGE TRUE
J 2
(-6625 2825);
DISPLAY 0.872340 (-6625 2825);
PAINT GREEN (-6625 2825);
DISPLAY INVISIBLE (-6625 2825);
FORCEPROP 1 LAST COMMENT_BODY TRUE
J 2
(-6255 2855);
DISPLAY 0.872340 (-6255 2855);
PAINT GREEN (-6255 2855);
DISPLAY INVISIBLE (-6255 2855);
FORCEPROP 2 LAST PATH I828
J 0
(-6550 3000);
DISPLAY 1.021277 (-6550 3000);
DISPLAY INVISIBLE (-6550 3000);
FORCEADD OFFPAGE..2
R 2
(-6300 2900);
FORCEPROP 2 LAST $XR0 86 
J 0
(-6524 2900);
DISPLAY 0.638298 (-6524 2900);
PAINT MONO (-6524 2900);
FORCEPROP 2 LAST CDS_LIB standard
J 0
(-6300 2900);
DISPLAY INVISIBLE (-6300 2900);
FORCEPROP 1 LAST OFFPAGE TRUE
J 2
(-6625 2775);
DISPLAY 0.872340 (-6625 2775);
PAINT GREEN (-6625 2775);
DISPLAY INVISIBLE (-6625 2775);
FORCEPROP 1 LAST COMMENT_BODY TRUE
J 2
(-6255 2805);
DISPLAY 0.872340 (-6255 2805);
PAINT GREEN (-6255 2805);
DISPLAY INVISIBLE (-6255 2805);
FORCEPROP 2 LAST PATH I829
J 0
(-6550 2950);
DISPLAY 1.021277 (-6550 2950);
DISPLAY INVISIBLE (-6550 2950);
FORCEADD OFFPAGE..1
(-6300 2800);
FORCEPROP 2 LAST $XR0 86 
J 0
(-6521 2800);
DISPLAY 0.638298 (-6521 2800);
PAINT MONO (-6521 2800);
FORCEPROP 2 LAST CDS_LIB standard
J 0
(-6300 2800);
DISPLAY INVISIBLE (-6300 2800);
FORCEPROP 1 LAST OFFPAGE TRUE
J 0
(-5975 2675);
DISPLAY 0.872340 (-5975 2675);
PAINT GREEN (-5975 2675);
DISPLAY INVISIBLE (-5975 2675);
FORCEPROP 1 LAST COMMENT_BODY TRUE
J 0
(-6175 2700);
DISPLAY 0.872340 (-6175 2700);
PAINT GREEN (-6175 2700);
DISPLAY INVISIBLE (-6175 2700);
FORCEPROP 2 LAST PATH I830
J 0
(-6550 2850);
DISPLAY 1.021277 (-6550 2850);
DISPLAY INVISIBLE (-6550 2850);
FORCEADD OFFPAGE..2
R 2
(-6300 2600);
FORCEPROP 2 LAST $XR0 86 
J 0
(-6524 2600);
DISPLAY 0.638298 (-6524 2600);
PAINT MONO (-6524 2600);
FORCEPROP 2 LAST CDS_LIB standard
J 0
(-6300 2600);
DISPLAY INVISIBLE (-6300 2600);
FORCEPROP 1 LAST OFFPAGE TRUE
J 2
(-6625 2475);
DISPLAY 0.872340 (-6625 2475);
PAINT GREEN (-6625 2475);
DISPLAY INVISIBLE (-6625 2475);
FORCEPROP 1 LAST COMMENT_BODY TRUE
J 2
(-6255 2505);
DISPLAY 0.872340 (-6255 2505);
PAINT GREEN (-6255 2505);
DISPLAY INVISIBLE (-6255 2505);
FORCEPROP 2 LAST PATH I831
J 0
(-6550 2650);
DISPLAY 1.021277 (-6550 2650);
DISPLAY INVISIBLE (-6550 2650);
FORCEADD OFFPAGE..5
(-6300 2700);
FORCEPROP 2 LAST $XR0 86 
J 0
(-6524 2700);
DISPLAY 0.638298 (-6524 2700);
PAINT MONO (-6524 2700);
FORCEPROP 2 LAST CDS_LIB mstr_standard
J 0
(-6300 2700);
DISPLAY INVISIBLE (-6300 2700);
FORCEPROP 1 LAST OFFPAGE TRUE
J 0
(-5975 2575);
DISPLAY 0.872340 (-5975 2575);
PAINT GREEN (-5975 2575);
DISPLAY INVISIBLE (-5975 2575);
FORCEPROP 1 LAST COMMENT_BODY TRUE
J 0
(-6200 2625);
DISPLAY 0.872340 (-6200 2625);
PAINT GREEN (-6200 2625);
DISPLAY INVISIBLE (-6200 2625);
FORCEPROP 2 LAST PATH I832
J 0
(-6550 2750);
DISPLAY 1.021277 (-6550 2750);
DISPLAY INVISIBLE (-6550 2750);
FORCEADD OFFPAGE..2
R 2
(-6300 2550);
FORCEPROP 2 LAST $XR0 86 
J 0
(-6524 2550);
DISPLAY 0.638298 (-6524 2550);
PAINT MONO (-6524 2550);
FORCEPROP 2 LAST CDS_LIB standard
J 0
(-6300 2550);
DISPLAY INVISIBLE (-6300 2550);
FORCEPROP 1 LAST OFFPAGE TRUE
J 2
(-6625 2425);
DISPLAY 0.872340 (-6625 2425);
PAINT GREEN (-6625 2425);
DISPLAY INVISIBLE (-6625 2425);
FORCEPROP 1 LAST COMMENT_BODY TRUE
J 2
(-6255 2455);
DISPLAY 0.872340 (-6255 2455);
PAINT GREEN (-6255 2455);
DISPLAY INVISIBLE (-6255 2455);
FORCEPROP 2 LAST PATH I833
J 0
(-6550 2600);
DISPLAY 1.021277 (-6550 2600);
DISPLAY INVISIBLE (-6550 2600);
FORCEADD OFFPAGE..1
(-6300 2450);
FORCEPROP 2 LAST $XR0 86 
J 0
(-6521 2450);
DISPLAY 0.638298 (-6521 2450);
PAINT MONO (-6521 2450);
FORCEPROP 2 LAST CDS_LIB standard
J 0
(-6300 2450);
DISPLAY INVISIBLE (-6300 2450);
FORCEPROP 1 LAST OFFPAGE TRUE
J 0
(-5975 2325);
DISPLAY 0.872340 (-5975 2325);
PAINT GREEN (-5975 2325);
DISPLAY INVISIBLE (-5975 2325);
FORCEPROP 1 LAST COMMENT_BODY TRUE
J 0
(-6175 2350);
DISPLAY 0.872340 (-6175 2350);
PAINT GREEN (-6175 2350);
DISPLAY INVISIBLE (-6175 2350);
FORCEPROP 2 LAST PATH I834
J 0
(-6550 2500);
DISPLAY 1.021277 (-6550 2500);
DISPLAY INVISIBLE (-6550 2500);
FORCEADD OFFPAGE..5
(-6300 2350);
FORCEPROP 2 LAST $XR0 86 
J 0
(-6524 2350);
DISPLAY 0.638298 (-6524 2350);
PAINT MONO (-6524 2350);
FORCEPROP 2 LAST CDS_LIB standard
J 0
(-6300 2350);
DISPLAY INVISIBLE (-6300 2350);
FORCEPROP 1 LAST OFFPAGE TRUE
J 0
(-5975 2225);
DISPLAY 0.872340 (-5975 2225);
PAINT GREEN (-5975 2225);
DISPLAY INVISIBLE (-5975 2225);
FORCEPROP 1 LAST COMMENT_BODY TRUE
J 0
(-6200 2275);
DISPLAY 0.872340 (-6200 2275);
PAINT GREEN (-6200 2275);
DISPLAY INVISIBLE (-6200 2275);
FORCEPROP 2 LAST PATH I835
J 0
(-6550 2400);
DISPLAY 1.021277 (-6550 2400);
DISPLAY INVISIBLE (-6550 2400);
FORCEADD OFFPAGE..5
(-6300 2150);
FORCEPROP 2 LAST $XR0 86 
J 0
(-6524 2150);
DISPLAY 0.638298 (-6524 2150);
PAINT MONO (-6524 2150);
FORCEPROP 2 LAST CDS_LIB standard
J 0
(-6300 2150);
DISPLAY INVISIBLE (-6300 2150);
FORCEPROP 1 LAST OFFPAGE TRUE
J 0
(-5975 2025);
DISPLAY 0.872340 (-5975 2025);
PAINT GREEN (-5975 2025);
DISPLAY INVISIBLE (-5975 2025);
FORCEPROP 1 LAST COMMENT_BODY TRUE
J 0
(-6200 2075);
DISPLAY 0.872340 (-6200 2075);
PAINT GREEN (-6200 2075);
DISPLAY INVISIBLE (-6200 2075);
FORCEPROP 2 LAST PATH I836
J 0
(-6550 2200);
DISPLAY 1.021277 (-6550 2200);
DISPLAY INVISIBLE (-6550 2200);
FORCEADD Q_RES..1
(-6600 2250);
FORCEPROP 1 LAST LOCATION R375
J 0
(-6925 2250);
DISPLAY 0.489362 (-6925 2250);
PAINT SKYBLUE (-6925 2250);
FORCEPROP 0 LAST $SEC 1
J 0
(-6775 2300);
DISPLAY 0.680851 (-6775 2300);
PAINT MONO (-6775 2300);
DISPLAY INVISIBLE (-6775 2300);
FORCEPROP 0 LAST CDS_SEC 1
J 0
(-6775 2300);
DISPLAY 1.021277 (-6775 2300);
DISPLAY INVISIBLE (-6775 2300);
FORCEPROP 1 LASTPIN (-6700 2250) $PN 1
J 0
(-6688 2262);
DISPLAY 0.489362 (-6688 2262);
PAINT MONO (-6688 2262);
FORCEPROP 1 LASTPIN (-6500 2250) $PN 2
J 0
(-6538 2262);
DISPLAY 0.489362 (-6538 2262);
PAINT MONO (-6538 2262);
FORCEPROP 1 LAST TOLERANCE 1%
J 0
(-6325 2250);
DISPLAY 0.489362 (-6325 2250);
PAINT SKYBLUE (-6325 2250);
FORCEPROP 1 LAST VALUE 15
J 2
(-6375 2250);
DISPLAY 0.489362 (-6375 2250);
PAINT SKYBLUE (-6375 2250);
FORCEPROP 1 LAST PACK_TYPE 0402LF
J 0
(-6925 2225);
DISPLAY 0.489362 (-6925 2225);
PAINT SKYBLUE (-6925 2225);
FORCEPROP 1 LAST MATERIAL CHIP
J 0
(-6725 2375);
DISPLAY 0.638298 (-6725 2375);
PAINT SKYBLUE (-6725 2375);
DISPLAY INVISIBLE (-6725 2375);
FORCEPROP 1 LAST WATTAGE 1/16W
J 2
(-6375 2375);
DISPLAY 0.638298 (-6375 2375);
PAINT SKYBLUE (-6375 2375);
DISPLAY INVISIBLE (-6375 2375);
FORCEPROP 2 LAST CDS_LIB pure_quanta
J 0
(-6600 2250);
DISPLAY INVISIBLE (-6600 2250);
FORCEPROP 1 LAST PATH I837
J 0
(-6650 2400);
DISPLAY 0.978723 (-6650 2400);
PAINT WHITE (-6650 2400);
DISPLAY INVISIBLE (-6650 2400);
FORCEPROP 1 LAST PART_NUMBER CS01502FB03
J 0
(-6475 2225);
DISPLAY 0.489362 (-6475 2225);
PAINT SKYBLUE (-6475 2225);
DISPLAY INVISIBLE (-6475 2225);
FORCEADD OFFPAGE..1
(-7900 2250);
FORCEPROP 2 LAST $XR0 86 
J 0
(-8151 2250);
DISPLAY 0.638298 (-8151 2250);
PAINT MONO (-8151 2250);
FORCEPROP 2 LAST CDS_LIB mstr_standard
J 0
(-7900 2250);
DISPLAY INVISIBLE (-7900 2250);
FORCEPROP 1 LAST OFFPAGE TRUE
J 0
(-7575 2125);
DISPLAY 0.872340 (-7575 2125);
PAINT GREEN (-7575 2125);
DISPLAY INVISIBLE (-7575 2125);
FORCEPROP 1 LAST COMMENT_BODY TRUE
J 0
(-7775 2150);
DISPLAY 0.872340 (-7775 2150);
PAINT GREEN (-7775 2150);
DISPLAY INVISIBLE (-7775 2150);
FORCEPROP 2 LAST PATH I838
J 0
(-8175 2300);
DISPLAY 1.021277 (-8175 2300);
DISPLAY INVISIBLE (-8175 2300);
FORCEADD QUANTA_TITLE_BLOCK_C..1
(-100 100);
FORCEPROP 0 LAST CDS_CON_LAST_MODIFIED Thu Sep 14 16:11:48 2023
J 0
(-1985 115);
DISPLAY INVISIBLE (-1985 115);
FORCEPROP 1 LAST CUSTOM_TXT_CDS <CON_LAST_MODIFIED>
J 0
(-1985 115);
DISPLAY 0.978723 (-1985 115);
FORCEPROP 2 LAST CUSTOM_TXT_CDS <XR_PAGE_TITLE>
J 0
(-7990 5350);
DISPLAY 0.638298 (-7990 5350);
PAINT PINK (-7990 5350);
DISPLAY INVISIBLE (-7990 5350);
FORCEPROP 1 LAST CUSTOM_TXT_CDS <NAME_2>
J 0
(-3275 150);
FORCEPROP 1 LAST CUSTOM_TXT_CDS <NAME_1>
J 0
(-3275 275);
FORCEPROP 1 LAST CUSTOM_TXT_CDS <Q_NUMBER>
J 0
(-1503 203);
DISPLAY 1.212766 (-1503 203);
FORCEPROP 1 LAST CUSTOM_TXT_CDS <Q_PROJ>
J 0
(-2482 202);
DISPLAY 1.212766 (-2482 202);
FORCEPROP 1 LAST CUSTOM_TXT_CDS <Q_REV>
J 0
(-284 203);
DISPLAY 1.212766 (-284 203);
FORCEPROP 1 LAST CUSTOM_TXT_CDS <CON_PAGE_NUM> OF <CON_TOTAL_PAGES>
J 0
(-546 118);
DISPLAY 0.978723 (-546 118);
FORCEPROP 1 LAST Q_TITLE CPU0 DDR CHA
J 0
(-9425 150);
DISPLAY 2.446809 (-9425 150);
PAINT GREEN (-9425 150);
FORCEPROP 2 LAST PAGE_BORDER TRUE
J 0
(-7990 5350);
DISPLAY 0.638298 (-7990 5350);
PAINT PINK (-7990 5350);
DISPLAY INVISIBLE (-7990 5350);
FORCEPROP 1 LAST CDS_LMAN_SYM_OUTLINE -9475,6775,100,-125
J 0
(-100 100);
DISPLAY 0.468085 (-100 100);
PAINT GREEN (-100 100);
DISPLAY INVISIBLE (-100 100);
FORCEPROP 2 LAST CDS_LIB pure_quanta
J 0
(-100 100);
DISPLAY INVISIBLE (-100 100);
FORCEPROP 2 LAST CDS_XR_PAGE_TITLE CR-10 : @T6G_MB_LIB.T6G(SCH_1):PAGE10
J 0
(-7990 5350);
DISPLAY 0.638298 (-7990 5350);
PAINT PINK (-7990 5350);
DISPLAY INVISIBLE (-7990 5350);
FORCEPROP 1 LAST Q_DEPT BU9
J 1
(-3863 149);
DISPLAY 1.957447 (-3863 149);
PAINT GREEN (-3863 149);
DISPLAY INVISIBLE (-3863 149);
FORCEPROP 1 LAST COMMENT_BODY TRUE
J 0
(-88 87);
DISPLAY 0.978723 (-88 87);
PAINT GREEN (-88 87);
DISPLAY INVISIBLE (-88 87);
FORCEADD CAD_NOTE..1
(-7550 2500);
FORCEPROP 0 LAST L1 R1941 PLACE CLOSE TO DIMM < 25MM
J 0
(-7700 2375);
DISPLAY 0.617021 (-7700 2375);
PAINT WHITE (-7700 2375);
FORCEPROP 2 LAST CDS_LIB pure_quanta_power
J 0
(-7550 2500);
DISPLAY INVISIBLE (-7550 2500);
FORCEPROP 1 LAST COMMENT_BODY TRUE
J 0
(-7525 2600);
DISPLAY 0.574468 (-7525 2600);
PAINT WHITE (-7525 2600);
DISPLAY INVISIBLE (-7525 2600);
WIRE 17 -1 (-2975 5975)(-2975 5925);
WIRE 17 -1 (-2975 6025)(-2975 5975);
WIRE 17 -1 (-2975 5925)(-2975 5875);
WIRE 17 -1 (-2975 5875)(-2975 5825);
WIRE 17 -1 (-2975 6075)(-2975 6025);
WIRE 17 -1 (-2975 6125)(-2975 6075);
WIRE 17 -1 (-2975 5825)(-2975 5775);
WIRE 17 -1 (-2975 5775)(-2975 5675);
WIRE 17 -1 (-2975 6125)(-2350 6125);
FORCEPROP 2 LAST SIG_NAME M_A_CPU0_SA_DQ<31:0>
J 0
(-2960 6135);
DISPLAY 0.489362 (-2960 6135);
WIRE 17 -1 (-2975 5675)(-2975 5625);
WIRE 17 -1 (-2975 5625)(-2975 5575);
WIRE 17 -1 (-2975 5575)(-2975 5525);
WIRE 17 -1 (-2975 5525)(-2975 5475);
WIRE 17 -1 (-2975 5475)(-2975 5425);
WIRE 17 -1 (-2975 5425)(-2975 5375);
WIRE 17 -1 (-2975 5375)(-2975 5325);
WIRE 17 -1 (-2975 5225)(-2975 5325);
WIRE 17 -1 (-2975 5175)(-2975 5225);
WIRE 17 -1 (-2975 5125)(-2975 5175);
WIRE 17 -1 (-2975 5075)(-2975 5125);
WIRE 17 -1 (-2975 5075)(-2975 5025);
WIRE 17 -1 (-2975 5025)(-2975 4975);
WIRE 17 -1 (-2975 4975)(-2975 4925);
WIRE 17 -1 (-2975 4925)(-2975 4875);
WIRE 17 -1 (-2975 4875)(-2975 4775);
WIRE 17 -1 (-2975 4775)(-2975 4725);
WIRE 17 -1 (-2975 4725)(-2975 4675);
WIRE 17 -1 (-2975 4675)(-2975 4625);
WIRE 17 -1 (-2975 4575)(-2975 4625);
WIRE 17 -1 (-2975 4525)(-2975 4575);
WIRE 17 -1 (-2975 4475)(-2975 4525);
WIRE 17 -1 (-2975 4425)(-2975 4475);
WIRE 17 -1 (-2975 4225)(-2975 4175);
WIRE 17 -1 (-2975 4275)(-2975 4225);
WIRE 17 -1 (-2975 4175)(-2975 4125);
WIRE 17 -1 (-2975 4125)(-2975 4075);
WIRE 17 -1 (-2975 4325)(-2975 4275);
WIRE 17 -1 (-2975 4325)(-2350 4325);
FORCEPROP 2 LAST SIG_NAME M_A_CPU0_SB_DQ<31:0>
J 0
(-2935 4335);
DISPLAY 0.489362 (-2935 4335);
WIRE 17 -1 (-2975 4075)(-2975 4025);
WIRE 17 -1 (-2975 4025)(-2975 3975);
WIRE 17 -1 (-2975 3975)(-2975 3875);
WIRE 17 -1 (-2975 3875)(-2975 3825);
WIRE 17 -1 (-2975 3825)(-2975 3775);
WIRE 17 -1 (-2975 3775)(-2975 3725);
WIRE 17 -1 (-2975 3725)(-2975 3675);
WIRE 17 -1 (-2975 3675)(-2975 3625);
WIRE 17 -1 (-2975 3625)(-2975 3575);
WIRE 17 -1 (-2975 3575)(-2975 3525);
WIRE 17 -1 (-2975 3425)(-2975 3525);
WIRE 17 -1 (-2975 3375)(-2975 3425);
WIRE 17 -1 (-2975 3325)(-2975 3375);
WIRE 17 -1 (-2975 3275)(-2975 3325);
WIRE 17 -1 (-2975 3275)(-2975 3225);
WIRE 17 -1 (-2975 3225)(-2975 3175);
WIRE 17 -1 (-2975 3175)(-2975 3125);
WIRE 17 -1 (-2975 3125)(-2975 3075);
WIRE 17 -1 (-2975 3075)(-2975 2975);
WIRE 17 -1 (-2975 2975)(-2975 2925);
WIRE 17 -1 (-2975 2925)(-2975 2875);
WIRE 17 -1 (-2975 2875)(-2975 2825);
WIRE 17 -1 (-2975 2775)(-2975 2825);
WIRE 17 -1 (-2975 2725)(-2975 2775);
WIRE 17 -1 (-2975 2675)(-2975 2725);
WIRE 17 -1 (-2975 2625)(-2975 2675);
WIRE 17 -1 (-2975 2525)(-2975 2550);
FORCEPROP 2 LAST SIG_NAME M_A_CPU0_SA_CB<7:0>
J 0
(-2985 2560);
DISPLAY 0.489362 (-2985 2560);
WIRE 17 -1 (-2975 2525)(-2975 2475);
WIRE 17 -1 (-2975 2425)(-2975 2475);
WIRE 17 -1 (-2975 2425)(-2975 2375);
WIRE 17 -1 (-2975 2325)(-2975 2375);
WIRE 17 -1 (-2975 2275)(-2975 2325);
WIRE 17 -1 (-2975 2225)(-2975 2275);
WIRE 17 -1 (-2975 2175)(-2975 2225);
WIRE 17 -1 (-2975 2075)(-2975 2100);
WIRE 17 -1 (-2975 2075)(-2975 2025);
WIRE 17 -1 (-2975 2100)(-2475 2100);
FORCEPROP 2 LAST SIG_NAME M_A_CPU0_SB_CB<7:0>
J 0
(-2960 2110);
DISPLAY 0.489362 (-2960 2110);
WIRE 17 -1 (-2975 1975)(-2975 2025);
WIRE 17 -1 (-2975 1975)(-2975 1925);
WIRE 17 -1 (-2975 1875)(-2975 1925);
WIRE 17 -1 (-2975 1825)(-2975 1875);
WIRE 17 -1 (-2975 1775)(-2975 1825);
WIRE 17 -1 (-2975 1725)(-2975 1775);
WIRE 17 -1 (-5600 6125)(-5600 6025);
WIRE 17 -1 (-5600 6125)(-6400 6125);
FORCEPROP 2 LAST SIG_NAME M_A_CPU0_SA_DQS_DP<9:0>
J 0
(-6410 6135);
DISPLAY 0.489362 (-6410 6135);
WIRE 17 -1 (-5600 6025)(-5600 5925);
WIRE 17 -1 (-5600 5925)(-5600 5825);
WIRE 17 -1 (-5600 5825)(-5600 5725);
WIRE 17 -1 (-5600 5625)(-5600 5725);
WIRE 17 -1 (-5600 5525)(-5600 5625);
WIRE 17 -1 (-5600 5425)(-5600 5525);
WIRE 17 -1 (-5600 5425)(-5600 5325);
WIRE 17 -1 (-5600 5325)(-5600 5225);
WIRE 17 -1 (-5800 6075)(-5800 5975);
WIRE 17 -1 (-5800 6075)(-6400 6075);
FORCEPROP 2 LAST SIG_NAME M_A_CPU0_SA_DQS_DN<9:0>
J 0
(-6410 6085);
DISPLAY 0.489362 (-6410 6085);
WIRE 17 -1 (-5800 5375)(-5800 5475);
WIRE 17 -1 (-5800 5375)(-5800 5275);
WIRE 17 -1 (-5800 5475)(-5800 5575);
WIRE 17 -1 (-5800 5575)(-5800 5675);
WIRE 17 -1 (-5800 5275)(-5800 5175);
WIRE 17 -1 (-5800 5775)(-5800 5675);
WIRE 17 -1 (-5800 5875)(-5800 5775);
WIRE 17 -1 (-5800 5975)(-5800 5875);
WIRE 17 -1 (-5600 5075)(-5600 4975);
WIRE 17 -1 (-5600 5075)(-6400 5075);
FORCEPROP 2 LAST SIG_NAME M_A_CPU0_SB_DQS_DP<9:0>
J 0
(-6435 5085);
DISPLAY 0.489362 (-6435 5085);
WIRE 17 -1 (-5600 4975)(-5600 4875);
WIRE 17 -1 (-5600 4875)(-5600 4775);
WIRE 17 -1 (-5600 4775)(-5600 4675);
WIRE 17 -1 (-5600 4575)(-5600 4675);
WIRE 17 -1 (-5600 4475)(-5600 4575);
WIRE 17 -1 (-5600 4375)(-5600 4475);
WIRE 17 -1 (-5600 4375)(-5600 4275);
WIRE 17 -1 (-5600 4275)(-5600 4175);
WIRE 17 -1 (-5800 4425)(-5800 4525);
WIRE 17 -1 (-5800 4325)(-5800 4425);
WIRE 17 -1 (-5800 4525)(-5800 4625);
WIRE 17 -1 (-5800 4725)(-5800 4625);
WIRE 17 -1 (-5800 4325)(-5800 4225);
WIRE 17 -1 (-5800 4225)(-5800 4125);
WIRE 17 -1 (-5800 4825)(-5800 4725);
WIRE 17 -1 (-5800 4925)(-5800 4825);
WIRE 17 -1 (-5800 5025)(-5800 4925);
WIRE 17 -1 (-5800 5025)(-6400 5025);
WIRE 17 -1 (-5750 3925)(-5750 3975);
WIRE 17 -1 (-5750 3875)(-5750 3925);
WIRE 17 -1 (-5750 3975)(-6250 3975);
FORCEPROP 2 LAST SIG_NAME M_A_CPU0_SA_CA<6:0>
J 0
(-6285 3985);
DISPLAY 0.489362 (-6285 3985);
WIRE 17 -1 (-5750 3525)(-5750 3575);
WIRE 17 -1 (-5750 3475)(-5750 3525);
WIRE 17 -1 (-5750 3575)(-6250 3575);
WIRE 17 -1 (-5750 3825)(-5750 3875);
WIRE 17 -1 (-5750 3425)(-5750 3475);
WIRE 17 -1 (-5750 3375)(-5750 3425);
WIRE 17 -1 (-5750 3325)(-5750 3375);
WIRE 17 -1 (-5750 3775)(-5750 3825);
WIRE 17 -1 (-5750 3725)(-5750 3775);
WIRE 17 -1 (-5750 3675)(-5750 3725);
WIRE 17 -1 (-5750 3275)(-5750 3325);
WIRE 17 -1 (-2975 2550)(-2475 2550);
WIRE 16 -1 (-7850 2250)(-6700 2250);
FORCEPROP 2 LAST SIG_NAME M_A_CPU0_ALERT_N
J 0
(-7710 2260);
DISPLAY 0.489362 (-7710 2260);
WIRE 16 -1 (-6500 2250)(-5150 2250);
FORCEPROP 2 LAST SIG_NAME M_A_CPU0_ALERT_R_N
J 0
(-6235 2260);
DISPLAY 0.489362 (-6235 2260);
FORCEPROP 2 LASTPROP $XRERR UNIQUE?
J 0
(-6475 2260);
DISPLAY 0.638298 (-6475 2260);
PAINT MONO (-6475 2260);
DISPLAY INVISIBLE (-6475 2260);
WIRE 16 -1 (-6250 1300)(-5150 1300);
FORCEPROP 2 LAST SIG_NAME TP_M_A_CPU0_SA_TEST39A
J 0
(-6235 1310);
DISPLAY 0.489362 (-6235 1310);
FORCEPROP 2 LASTPROP $XRERR UNIQUE?
J 0
(-6490 1300);
DISPLAY 0.638298 (-6490 1300);
PAINT MONO (-6490 1300);
DISPLAY INVISIBLE (-6490 1300);
WIRE 16 -1 (-6250 1250)(-5150 1250);
FORCEPROP 2 LAST SIG_NAME TP_M_A_CPU0_SA_TEST40
J 0
(-6235 1260);
DISPLAY 0.489362 (-6235 1260);
FORCEPROP 2 LASTPROP $XRERR UNIQUE?
J 0
(-6490 1250);
DISPLAY 0.638298 (-6490 1250);
PAINT MONO (-6490 1250);
DISPLAY INVISIBLE (-6490 1250);
WIRE 16 -1 (-6250 3100)(-5150 3100);
FORCEPROP 2 LAST SIG_NAME M_A_CPU0_CLK_DP<0>
J 0
(-6250 3110);
DISPLAY 0.489362 (-6250 3110);
WIRE 16 -1 (-6250 3050)(-5150 3050);
FORCEPROP 2 LAST SIG_NAME M_A_CPU0_CLK_DN<0>
J 0
(-6250 3060);
DISPLAY 0.489362 (-6250 3060);
WIRE 16 -1 (-6250 2950)(-5150 2950);
FORCEPROP 2 LAST SIG_NAME M_A_CPU0_SA_CS_N<0>
J 0
(-6250 2960);
DISPLAY 0.489362 (-6250 2960);
WIRE 16 -1 (-6250 2900)(-5150 2900);
FORCEPROP 2 LAST SIG_NAME M_A_CPU0_SA_CS_N<1>
J 0
(-6250 2910);
DISPLAY 0.489362 (-6250 2910);
WIRE 16 -1 (-6250 2800)(-5150 2800);
FORCEPROP 2 LAST SIG_NAME M_A_CPU0_SA_RSP<0>
J 0
(-6250 2810);
DISPLAY 0.489362 (-6250 2810);
WIRE 16 -1 (-6250 2600)(-5150 2600);
FORCEPROP 2 LAST SIG_NAME M_A_CPU0_SB_CS_N<0>
J 0
(-6250 2610);
DISPLAY 0.489362 (-6250 2610);
WIRE 16 -1 (-6250 2700)(-5150 2700);
FORCEPROP 2 LAST SIG_NAME M_A_CPU0_SA_PAR
J 0
(-6250 2710);
DISPLAY 0.489362 (-6250 2710);
WIRE 16 -1 (-6250 2550)(-5150 2550);
FORCEPROP 2 LAST SIG_NAME M_A_CPU0_SB_CS_N<1>
J 0
(-6250 2560);
DISPLAY 0.489362 (-6250 2560);
WIRE 16 -1 (-6250 2450)(-5150 2450);
FORCEPROP 2 LAST SIG_NAME M_A_CPU0_SB_RSP<0>
J 0
(-6250 2460);
DISPLAY 0.489362 (-6250 2460);
WIRE 16 -1 (-6250 2350)(-5150 2350);
FORCEPROP 2 LAST SIG_NAME M_A_CPU0_SB_PAR
J 0
(-6250 2360);
DISPLAY 0.489362 (-6250 2360);
WIRE 16 -1 (-6250 2150)(-5150 2150);
FORCEPROP 2 LAST SIG_NAME M_A_CPU0_RESET_N
J 0
(-6250 2160);
DISPLAY 0.489362 (-6250 2160);
WIRE 16 -1 (-5650 3250)(-5150 3250);
WIRE 16 -1 (-5650 3650)(-5150 3650);
WIRE 16 -1 (-5650 3300)(-5150 3300);
WIRE 16 -1 (-5650 3700)(-5150 3700);
WIRE 16 -1 (-5650 3350)(-5150 3350);
WIRE 16 -1 (-5650 3750)(-5150 3750);
WIRE 16 -1 (-5650 3400)(-5150 3400);
WIRE 16 -1 (-5650 3800)(-5150 3800);
WIRE 16 -1 (-5650 3450)(-5150 3450);
WIRE 16 -1 (-5650 3850)(-5150 3850);
WIRE 16 -1 (-5650 3500)(-5150 3500);
WIRE 16 -1 (-5650 3900)(-5150 3900);
WIRE 16 -1 (-5650 3550)(-5150 3550);
WIRE 16 -1 (-5650 3950)(-5150 3950);
WIRE 16 -1 (-5700 4600)(-5150 4600);
WIRE 16 -1 (-5700 4700)(-5150 4700);
WIRE 16 -1 (-5700 4800)(-5150 4800);
WIRE 16 -1 (-5700 4900)(-5150 4900);
WIRE 16 -1 (-5700 5000)(-5150 5000);
WIRE 16 -1 (-5700 4100)(-5150 4100);
WIRE 16 -1 (-5700 4200)(-5150 4200);
WIRE 16 -1 (-5700 4300)(-5150 4300);
WIRE 16 -1 (-5700 4400)(-5150 4400);
WIRE 16 -1 (-5700 4500)(-5150 4500);
WIRE 16 -1 (-5500 4150)(-5150 4150);
WIRE 16 -1 (-5500 4250)(-5150 4250);
WIRE 16 -1 (-5500 4350)(-5150 4350);
WIRE 16 -1 (-5500 4450)(-5150 4450);
WIRE 16 -1 (-5500 4550)(-5150 4550);
WIRE 16 -1 (-5500 5050)(-5150 5050);
WIRE 16 -1 (-5500 4650)(-5150 4650);
WIRE 16 -1 (-5500 4750)(-5150 4750);
WIRE 16 -1 (-5500 4850)(-5150 4850);
WIRE 16 -1 (-5500 4950)(-5150 4950);
WIRE 16 -1 (-5700 5150)(-5150 5150);
WIRE 16 -1 (-5700 5250)(-5150 5250);
WIRE 16 -1 (-5700 5450)(-5150 5450);
WIRE 16 -1 (-5700 5550)(-5150 5550);
WIRE 16 -1 (-5700 5650)(-5150 5650);
WIRE 16 -1 (-5700 5750)(-5150 5750);
WIRE 16 -1 (-5700 5850)(-5150 5850);
WIRE 16 -1 (-5700 5350)(-5150 5350);
WIRE 16 -1 (-5700 5950)(-5150 5950);
WIRE 16 -1 (-5700 6050)(-5150 6050);
WIRE 16 -1 (-5500 5500)(-5150 5500);
WIRE 16 -1 (-5500 5600)(-5150 5600);
WIRE 16 -1 (-5500 5200)(-5150 5200);
WIRE 16 -1 (-5500 5300)(-5150 5300);
WIRE 16 -1 (-5500 5400)(-5150 5400);
WIRE 16 -1 (-5500 5700)(-5150 5700);
WIRE 16 -1 (-5500 5800)(-5150 5800);
WIRE 16 -1 (-5500 5900)(-5150 5900);
WIRE 16 -1 (-5500 6000)(-5150 6000);
WIRE 16 -1 (-5500 6100)(-5150 6100);
WIRE 16 -1 (-3075 1700)(-3550 1700);
WIRE 16 -1 (-3075 1750)(-3550 1750);
WIRE 16 -1 (-3075 1800)(-3550 1800);
WIRE 16 -1 (-3075 1850)(-3550 1850);
WIRE 16 -1 (-3075 1900)(-3550 1900);
WIRE 16 -1 (-3075 1950)(-3550 1950);
WIRE 16 -1 (-3075 2000)(-3550 2000);
WIRE 16 -1 (-3075 2150)(-3550 2150);
WIRE 16 -1 (-3075 2200)(-3550 2200);
WIRE 16 -1 (-3075 2050)(-3550 2050);
WIRE 16 -1 (-3075 2250)(-3550 2250);
WIRE 16 -1 (-3075 2300)(-3550 2300);
WIRE 16 -1 (-3075 2350)(-3550 2350);
WIRE 16 -1 (-3075 2400)(-3550 2400);
WIRE 16 -1 (-3075 2450)(-3550 2450);
WIRE 16 -1 (-3075 2500)(-3550 2500);
WIRE 16 -1 (-3075 2750)(-3550 2750);
WIRE 16 -1 (-3075 2800)(-3550 2800);
WIRE 16 -1 (-3075 2850)(-3550 2850);
WIRE 16 -1 (-3075 2900)(-3550 2900);
WIRE 16 -1 (-3075 2950)(-3550 2950);
WIRE 16 -1 (-3075 3050)(-3550 3050);
WIRE 16 -1 (-3075 2600)(-3550 2600);
WIRE 16 -1 (-3075 2650)(-3550 2650);
WIRE 16 -1 (-3075 2700)(-3550 2700);
WIRE 16 -1 (-3075 3350)(-3550 3350);
WIRE 16 -1 (-3075 3400)(-3550 3400);
WIRE 16 -1 (-3075 3500)(-3550 3500);
WIRE 16 -1 (-3075 3550)(-3550 3550);
WIRE 16 -1 (-3075 3100)(-3550 3100);
WIRE 16 -1 (-3075 3150)(-3550 3150);
WIRE 16 -1 (-3075 3200)(-3550 3200);
WIRE 16 -1 (-3075 3250)(-3550 3250);
WIRE 16 -1 (-3075 3300)(-3550 3300);
WIRE 16 -1 (-3075 3600)(-3550 3600);
WIRE 16 -1 (-3075 3650)(-3550 3650);
WIRE 16 -1 (-3075 3700)(-3550 3700);
WIRE 16 -1 (-3075 3750)(-3550 3750);
WIRE 16 -1 (-3075 3800)(-3550 3800);
WIRE 16 -1 (-3075 3850)(-3550 3850);
WIRE 16 -1 (-3075 3950)(-3550 3950);
WIRE 16 -1 (-3075 4000)(-3550 4000);
WIRE 16 -1 (-3550 4050)(-3075 4050);
WIRE 16 -1 (-3075 4200)(-3550 4200);
WIRE 16 -1 (-3075 4250)(-3550 4250);
WIRE 16 -1 (-3550 4300)(-3075 4300);
WIRE 16 -1 (-3550 4500)(-3075 4500);
WIRE 16 -1 (-3550 4550)(-3075 4550);
WIRE 16 -1 (-3550 4600)(-3075 4600);
WIRE 16 -1 (-3550 4400)(-3075 4400);
WIRE 16 -1 (-3550 4450)(-3075 4450);
WIRE 16 -1 (-3075 4100)(-3550 4100);
WIRE 16 -1 (-3075 4150)(-3550 4150);
WIRE 16 -1 (-3550 5050)(-3075 5050);
WIRE 16 -1 (-3550 5100)(-3075 5100);
WIRE 16 -1 (-3550 4650)(-3075 4650);
WIRE 16 -1 (-3550 4700)(-3075 4700);
WIRE 16 -1 (-3550 4750)(-3075 4750);
WIRE 16 -1 (-3550 4850)(-3075 4850);
WIRE 16 -1 (-3550 4900)(-3075 4900);
WIRE 16 -1 (-3550 4950)(-3075 4950);
WIRE 16 -1 (-3550 5000)(-3075 5000);
WIRE 16 -1 (-3550 5150)(-3075 5150);
WIRE 16 -1 (-3550 5200)(-3075 5200);
WIRE 16 -1 (-3550 5300)(-3075 5300);
WIRE 16 -1 (-3550 5350)(-3075 5350);
WIRE 16 -1 (-3550 5400)(-3075 5400);
WIRE 16 -1 (-3550 5600)(-3075 5600);
WIRE 16 -1 (-3550 5450)(-3075 5450);
WIRE 16 -1 (-3550 5500)(-3075 5500);
WIRE 16 -1 (-3550 5550)(-3075 5550);
WIRE 16 -1 (-3550 5950)(-3075 5950);
WIRE 16 -1 (-3550 6000)(-3075 6000);
WIRE 16 -1 (-3550 6050)(-3075 6050);
WIRE 16 -1 (-3550 6100)(-3075 6100);
WIRE 16 -1 (-3550 5650)(-3075 5650);
WIRE 16 -1 (-3550 5750)(-3075 5750);
WIRE 16 -1 (-3550 5800)(-3075 5800);
WIRE 16 -1 (-3550 5850)(-3075 5850);
WIRE 16 -1 (-3550 5900)(-3075 5900);
QUIT
